FILE_TYPE = MACRO_DRAWING;
SET COLOR_WIRE YELLOW;
SET COLOR_PROP ORANGE;
SET COLOR_DOT WHITE;
SET COLOR_ARC YELLOW;
SET COLOR_BODY GREEN;
SET COLOR_NOTE PURPLE;
SET PROP_DISPLAY VALUE;
SET PAGE_NUMBER P222;
FORCEADD OFFPAGE..1
(-7050 5975);
FORCEPROP 2 LAST $XR1 241 
J 0
(-7422 5975);
DISPLAY 0.638298 (-7422 5975);
PAINT MONO (-7422 5975);
FORCEPROP 2 LAST $XR0 240 
J 0
(-7302 5975);
DISPLAY 0.638298 (-7302 5975);
PAINT MONO (-7302 5975);
FORCEPROP 2 LAST CDS_LIB standard
J 0
(-7050 5975);
PAINT MONO (-7050 5975);
DISPLAY INVISIBLE (-7050 5975);
FORCEPROP 1 LAST OFFPAGE TRUE
J 0
(-6725 5850);
DISPLAY 0.872340 (-6725 5850);
DISPLAY INVISIBLE (-6725 5850);
FORCEPROP 1 LAST COMMENT_BODY TRUE
J 0
(-6925 5875);
DISPLAY 0.872340 (-6925 5875);
PAINT GREEN (-6925 5875);
DISPLAY INVISIBLE (-6925 5875);
FORCEPROP 2 LAST PATH I1
J 0
(-7300 6025);
DISPLAY 1.021277 (-7300 6025);
DISPLAY INVISIBLE (-7300 6025);
FORCEADD UNIVERSAL_GND..1
(-5250 5750);
FORCEPROP 3 LASTPIN (-5250 5800) SIG_NAME GND\g
J 0
(-5240 5810);
DISPLAY 0.659574 (-5240 5810);
PAINT MONO (-5240 5810);
DISPLAY INVISIBLE (-5240 5810);
FORCEPROP 2 LAST CDS_LIB logical_power
J 0
(-5250 5750);
PAINT MONO (-5250 5750);
DISPLAY INVISIBLE (-5250 5750);
FORCEPROP 1 LAST HDL_POWER GND
J 1
(-5225 5675);
DISPLAY 0.872340 (-5225 5675);
PAINT GREEN (-5225 5675);
DISPLAY INVISIBLE (-5225 5675);
FORCEPROP 1 LAST PATH I10
J 0
(-5175 5750);
DISPLAY 0.872340 (-5175 5750);
PAINT AQUA (-5175 5750);
DISPLAY INVISIBLE (-5175 5750);
FORCEADD LTC4307CMS8..1
(-4850 6025);
FORCEPROP 1 LAST PART_NUMBER AL004307000
J 0
(-5100 6285);
DISPLAY 0.723404 (-5100 6285);
PAINT GREEN (-5100 6285);
DISPLAY INVISIBLE (-5100 6285);
FORCEPROP 2 LAST VALUE LTC4307CMS8
J 0
(-5100 6375);
DISPLAY 1.021277 (-5100 6375);
FORCEPROP 2 LAST PART_TYPE SMLF
J 0
(-5100 6425);
DISPLAY 1.021277 (-5100 6425);
FORCEPROP 1 LAST MATERIAL IC
J 0
(-5100 6235);
DISPLAY 0.723404 (-5100 6235);
PAINT GREEN (-5100 6235);
FORCEPROP 1 LAST LOCATION U200
J 0
(-5100 6330);
DISPLAY 0.723404 (-5100 6330);
PAINT GREEN (-5100 6330);
FORCEPROP 0 LASTPIN (-5250 6175) $PN 1
J 2
(-5260 6185);
DISPLAY 0.680851 (-5260 6185);
PAINT MONO (-5260 6185);
FORCEPROP 0 LASTPIN (-5250 5875) $PN 4
J 2
(-5260 5885);
DISPLAY 0.680851 (-5260 5885);
PAINT MONO (-5260 5885);
FORCEPROP 0 LASTPIN (-4450 5875) $PN 5
J 0
(-4440 5885);
DISPLAY 0.680851 (-4440 5885);
PAINT MONO (-4440 5885);
FORCEPROP 0 LASTPIN (-5250 6075) $PN 3
J 2
(-5260 6085);
DISPLAY 0.680851 (-5260 6085);
PAINT MONO (-5260 6085);
FORCEPROP 0 LASTPIN (-4450 6075) $PN 2
J 0
(-4440 6085);
DISPLAY 0.680851 (-4440 6085);
PAINT MONO (-4440 6085);
FORCEPROP 0 LASTPIN (-5250 5975) $PN 6
J 2
(-5260 5985);
DISPLAY 0.680851 (-5260 5985);
PAINT MONO (-5260 5985);
FORCEPROP 0 LASTPIN (-4450 5975) $PN 7
J 0
(-4440 5985);
DISPLAY 0.680851 (-4440 5985);
PAINT MONO (-4440 5985);
FORCEPROP 0 LASTPIN (-4450 6175) $PN 8
J 0
(-4440 6185);
DISPLAY 0.680851 (-4440 6185);
PAINT MONO (-4440 6185);
FORCEPROP 2 LAST CDS_LIB pure_quanta
J 0
(-4850 6025);
DISPLAY INVISIBLE (-4850 6025);
FORCEPROP 1 LAST NEEDS_NO_SIZE TRUE
J 0
(-4850 6025);
DISPLAY 0.468085 (-4850 6025);
PAINT GREEN (-4850 6025);
DISPLAY INVISIBLE (-4850 6025);
FORCEPROP 1 LAST PATH I11
J 0
(-4625 6230);
DISPLAY 0.723404 (-4625 6230);
PAINT GREEN (-4625 6230);
DISPLAY INVISIBLE (-4625 6230);
FORCEPROP 0 LAST $SEC 1
J 0
(-5100 6475);
DISPLAY 0.680851 (-5100 6475);
PAINT MONO (-5100 6475);
DISPLAY INVISIBLE (-5100 6475);
FORCEPROP 0 LAST CDS_SEC 1
J 0
(-5100 6475);
DISPLAY 1.021277 (-5100 6475);
DISPLAY INVISIBLE (-5100 6475);
FORCEADD Q_RES..1
(-4875 5550);
FORCEPROP 1 LAST PART_NUMBER CS00002JB13
J 0
(-4975 5500);
DISPLAY 0.404255 (-4975 5500);
DISPLAY INVISIBLE (-4975 5500);
FORCEPROP 1 LAST MATERIAL EMPTY
J 0
(-4575 5550);
DISPLAY 0.510638 (-4575 5550);
PAINT RED (-4575 5550);
FORCEPROP 1 LAST WATTAGE 1/16W
J 2
(-4750 5450);
DISPLAY 0.404255 (-4750 5450);
FORCEPROP 1 LAST PACK_TYPE 0402LF
J 0
(-4975 5450);
DISPLAY 0.404255 (-4975 5450);
FORCEPROP 1 LAST VALUE 0
J 2
(-4725 5550);
DISPLAY 0.510638 (-4725 5550);
FORCEPROP 1 LAST TOLERANCE 5%
J 0
(-4650 5550);
DISPLAY 0.510638 (-4650 5550);
FORCEPROP 1 LAST $LOCATION R2987
J 0
(-5050 5550);
DISPLAY 0.638298 (-5050 5550);
FORCEPROP 1 LASTPIN (-4975 5550) $PN 1
J 0
(-4963 5562);
DISPLAY 0.787234 (-4963 5562);
PAINT MONO (-4963 5562);
FORCEPROP 1 LASTPIN (-4775 5550) $PN 2
J 0
(-4813 5562);
DISPLAY 0.787234 (-4813 5562);
PAINT MONO (-4813 5562);
FORCEPROP 2 LAST CDS_LIB pure_quanta
J 0
(-4875 5550);
DISPLAY INVISIBLE (-4875 5550);
FORCEPROP 1 LAST PATH I12
J 0
(-4925 5700);
DISPLAY 0.978723 (-4925 5700);
PAINT WHITE (-4925 5700);
DISPLAY INVISIBLE (-4925 5700);
FORCEPROP 2 LAST CDS_LOCATION R2987
J 0
(-4925 5750);
DISPLAY 1.021277 (-4925 5750);
DISPLAY INVISIBLE (-4925 5750);
FORCEPROP 2 LAST $SEC 1
J 0
(-4925 5750);
DISPLAY 0.680851 (-4925 5750);
PAINT MONO (-4925 5750);
DISPLAY INVISIBLE (-4925 5750);
FORCEPROP 2 LAST CDS_SEC 1
J 0
(-4925 5750);
DISPLAY 1.021277 (-4925 5750);
DISPLAY INVISIBLE (-4925 5750);
FORCEADD Q_RES..1
(-4875 5625);
FORCEPROP 1 LAST PART_NUMBER CS00002JB13
J 0
(-4975 5575);
DISPLAY 0.404255 (-4975 5575);
DISPLAY INVISIBLE (-4975 5575);
FORCEPROP 1 LAST MATERIAL EMPTY
J 0
(-4575 5625);
DISPLAY 0.510638 (-4575 5625);
PAINT RED (-4575 5625);
FORCEPROP 1 LAST VALUE 0
J 2
(-4725 5625);
DISPLAY 0.510638 (-4725 5625);
FORCEPROP 1 LAST $LOCATION R2986
J 0
(-5050 5625);
DISPLAY 0.638298 (-5050 5625);
FORCEPROP 1 LASTPIN (-4975 5625) $PN 1
J 0
(-4963 5637);
DISPLAY 0.787234 (-4963 5637);
PAINT MONO (-4963 5637);
FORCEPROP 1 LASTPIN (-4775 5625) $PN 2
J 0
(-4813 5637);
DISPLAY 0.787234 (-4813 5637);
PAINT MONO (-4813 5637);
FORCEPROP 1 LAST WATTAGE 1/16W
J 2
(-4750 5525);
DISPLAY 0.404255 (-4750 5525);
DISPLAY INVISIBLE (-4750 5525);
FORCEPROP 1 LAST TOLERANCE 5%
J 0
(-4650 5625);
DISPLAY 0.510638 (-4650 5625);
DISPLAY INVISIBLE (-4650 5625);
FORCEPROP 1 LAST PACK_TYPE 0402LF
J 0
(-4975 5525);
DISPLAY 0.404255 (-4975 5525);
DISPLAY INVISIBLE (-4975 5525);
FORCEPROP 2 LAST CDS_LIB pure_quanta
J 0
(-4875 5625);
DISPLAY INVISIBLE (-4875 5625);
FORCEPROP 1 LAST PATH I13
J 0
(-4925 5775);
DISPLAY 0.978723 (-4925 5775);
PAINT WHITE (-4925 5775);
DISPLAY INVISIBLE (-4925 5775);
FORCEPROP 0 LAST CDS_LOCATION R2986
J 0
(-4750 5725);
DISPLAY 1.021277 (-4750 5725);
DISPLAY INVISIBLE (-4750 5725);
FORCEPROP 0 LAST $SEC 1
J 0
(-4750 5725);
DISPLAY 0.680851 (-4750 5725);
PAINT MONO (-4750 5725);
DISPLAY INVISIBLE (-4750 5725);
FORCEPROP 0 LAST CDS_SEC 1
J 0
(-4750 5725);
DISPLAY 1.021277 (-4750 5725);
DISPLAY INVISIBLE (-4750 5725);
FORCEADD UNIVERSAL_GND..1
(-5050 6900);
FORCEPROP 3 LASTPIN (-5050 6950) SIG_NAME GND\g
J 0
(-5040 6960);
DISPLAY 0.659574 (-5040 6960);
PAINT MONO (-5040 6960);
DISPLAY INVISIBLE (-5040 6960);
FORCEPROP 2 LAST CDS_LIB logical_power
J 0
(-5050 6900);
DISPLAY INVISIBLE (-5050 6900);
FORCEPROP 1 LAST HDL_POWER GND
J 1
(-5025 6825);
DISPLAY 0.872340 (-5025 6825);
PAINT GREEN (-5025 6825);
DISPLAY INVISIBLE (-5025 6825);
FORCEPROP 1 LAST PATH I14
J 0
(-4975 6900);
DISPLAY 0.872340 (-4975 6900);
PAINT AQUA (-4975 6900);
DISPLAY INVISIBLE (-4975 6900);
FORCEADD UNIVERSAL_GND..1
(-4825 4100);
FORCEPROP 3 LASTPIN (-4825 4150) SIG_NAME GND\g
J 0
(-4815 4160);
DISPLAY 0.659574 (-4815 4160);
PAINT MONO (-4815 4160);
DISPLAY INVISIBLE (-4815 4160);
FORCEPROP 2 LAST CDS_LIB logical_power
J 0
(-4825 4100);
DISPLAY INVISIBLE (-4825 4100);
FORCEPROP 1 LAST HDL_POWER GND
J 1
(-4800 4025);
DISPLAY 0.872340 (-4800 4025);
PAINT GREEN (-4800 4025);
DISPLAY INVISIBLE (-4800 4025);
FORCEPROP 1 LAST PATH I15
J 0
(-4750 4100);
DISPLAY 0.872340 (-4750 4100);
PAINT AQUA (-4750 4100);
DISPLAY INVISIBLE (-4750 4100);
FORCEADD Q_RES..2
(-4825 4300);
FORCEPROP 1 LAST PART_NUMBER CS31002FB08
J 0
(-4785 4125);
DISPLAY 0.510638 (-4785 4125);
DISPLAY INVISIBLE (-4785 4125);
FORCEPROP 1 LAST TOLERANCE 1%
J 0
(-4780 4325);
DISPLAY 0.510638 (-4780 4325);
FORCEPROP 1 LAST PACK_TYPE 0402LF
J 0
(-4785 4175);
DISPLAY 0.510638 (-4785 4175);
FORCEPROP 1 LAST MATERIAL CHIP
J 0
(-4785 4225);
DISPLAY 0.510638 (-4785 4225);
FORCEPROP 1 LAST VALUE 10K
J 0
(-4780 4375);
DISPLAY 0.510638 (-4780 4375);
FORCEPROP 1 LAST WATTAGE 1/16W
J 0
(-4785 4275);
DISPLAY 0.510638 (-4785 4275);
FORCEPROP 1 LAST $LOCATION R2666
J 0
(-4780 4425);
DISPLAY 0.978723 (-4780 4425);
FORCEPROP 1 LASTPIN (-4825 4400) $PN 1
J 0
(-4820 4362);
DISPLAY 0.787234 (-4820 4362);
PAINT MONO (-4820 4362);
FORCEPROP 1 LASTPIN (-4825 4200) $PN 2
J 0
(-4820 4210);
DISPLAY 0.787234 (-4820 4210);
PAINT MONO (-4820 4210);
FORCEPROP 2 LAST CDS_LIB pure_quanta
J 0
(-4825 4300);
DISPLAY INVISIBLE (-4825 4300);
FORCEPROP 1 LAST PATH I16
J 0
(-4775 4475);
DISPLAY 0.978723 (-4775 4475);
PAINT WHITE (-4775 4475);
DISPLAY INVISIBLE (-4775 4475);
FORCEPROP 0 LAST CDS_LOCATION R2666
J 0
(-4775 4475);
DISPLAY 1.021277 (-4775 4475);
DISPLAY INVISIBLE (-4775 4475);
FORCEPROP 0 LAST $SEC 1
J 0
(-4775 4475);
DISPLAY 0.680851 (-4775 4475);
PAINT MONO (-4775 4475);
DISPLAY INVISIBLE (-4775 4475);
FORCEPROP 0 LAST CDS_SEC 1
J 0
(-4775 4475);
DISPLAY 1.021277 (-4775 4475);
DISPLAY INVISIBLE (-4775 4475);
FORCEADD Q_RES..1
(-4050 4550);
FORCEPROP 1 LAST PART_NUMBER CS00002JB13
J 0
(-4175 4600);
DISPLAY 0.404255 (-4175 4600);
DISPLAY INVISIBLE (-4175 4600);
FORCEPROP 1 LAST TOLERANCE 5%
J 0
(-3825 4550);
DISPLAY 0.510638 (-3825 4550);
FORCEPROP 1 LAST VALUE 0
J 2
(-3850 4550);
DISPLAY 0.510638 (-3850 4550);
FORCEPROP 1 LAST MATERIAL CHIP
J 0
(-3750 4550);
DISPLAY 0.510638 (-3750 4550);
FORCEPROP 1 LAST LOCATION R3111
J 0
(-4275 4550);
DISPLAY 0.638298 (-4275 4550);
FORCEPROP 1 LASTPIN (-4150 4550) $PN 1
J 0
(-4138 4562);
DISPLAY 0.787234 (-4138 4562);
PAINT MONO (-4138 4562);
FORCEPROP 1 LASTPIN (-3950 4550) $PN 2
J 0
(-3988 4562);
DISPLAY 0.787234 (-3988 4562);
PAINT MONO (-3988 4562);
FORCEPROP 1 LAST PACK_TYPE 0402LF
J 0
(-4175 4650);
DISPLAY 0.404255 (-4175 4650);
DISPLAY INVISIBLE (-4175 4650);
FORCEPROP 1 LAST WATTAGE 1/16W
J 2
(-3950 4650);
DISPLAY 0.404255 (-3950 4650);
DISPLAY INVISIBLE (-3950 4650);
FORCEPROP 2 LAST CDS_LIB pure_quanta
J 0
(-4050 4550);
DISPLAY INVISIBLE (-4050 4550);
FORCEPROP 1 LAST PATH I17
J 0
(-4100 4700);
DISPLAY 0.978723 (-4100 4700);
PAINT WHITE (-4100 4700);
DISPLAY INVISIBLE (-4100 4700);
FORCEPROP 0 LAST $SEC 1
J 0
(-4275 4600);
DISPLAY 0.680851 (-4275 4600);
PAINT MONO (-4275 4600);
DISPLAY INVISIBLE (-4275 4600);
FORCEPROP 0 LAST CDS_SEC 1
J 0
(-4275 4600);
DISPLAY 1.021277 (-4275 4600);
DISPLAY INVISIBLE (-4275 4600);
FORCEADD Q_RES..1
(-4050 4650);
FORCEPROP 1 LAST PART_NUMBER CS03322FB03
J 0
(-4175 4700);
DISPLAY 0.404255 (-4175 4700);
DISPLAY INVISIBLE (-4175 4700);
FORCEPROP 1 LAST VALUE 33.2
J 2
(-3850 4650);
DISPLAY 0.510638 (-3850 4650);
FORCEPROP 1 LAST MATERIAL CHIP
J 0
(-3750 4650);
DISPLAY 0.510638 (-3750 4650);
FORCEPROP 1 LAST TOLERANCE 1%
J 0
(-3825 4650);
DISPLAY 0.510638 (-3825 4650);
FORCEPROP 1 LAST LOCATION R3112
J 0
(-4275 4650);
DISPLAY 0.638298 (-4275 4650);
FORCEPROP 1 LASTPIN (-4150 4650) $PN 1
J 0
(-4138 4662);
DISPLAY 0.787234 (-4138 4662);
PAINT MONO (-4138 4662);
FORCEPROP 1 LASTPIN (-3950 4650) $PN 2
J 0
(-3988 4662);
DISPLAY 0.787234 (-3988 4662);
PAINT MONO (-3988 4662);
FORCEPROP 2 LAST CDS_LIB pure_quanta
J 0
(-4050 4650);
DISPLAY INVISIBLE (-4050 4650);
FORCEPROP 1 LAST PACK_TYPE 0402LF
J 0
(-4175 4750);
DISPLAY 0.404255 (-4175 4750);
DISPLAY INVISIBLE (-4175 4750);
FORCEPROP 1 LAST WATTAGE 1/16W
J 2
(-3950 4750);
DISPLAY 0.404255 (-3950 4750);
DISPLAY INVISIBLE (-3950 4750);
FORCEPROP 1 LAST PATH I18
J 0
(-4100 4800);
DISPLAY 0.978723 (-4100 4800);
PAINT WHITE (-4100 4800);
DISPLAY INVISIBLE (-4100 4800);
FORCEPROP 0 LAST $SEC 1
J 0
(-4275 4700);
DISPLAY 0.680851 (-4275 4700);
PAINT MONO (-4275 4700);
DISPLAY INVISIBLE (-4275 4700);
FORCEPROP 0 LAST CDS_SEC 1
J 0
(-4275 4700);
DISPLAY 1.021277 (-4275 4700);
DISPLAY INVISIBLE (-4275 4700);
FORCEADD Q_RES..1
(-4050 4750);
FORCEPROP 1 LAST PART_NUMBER CS00002JB13
J 0
(-4150 4850);
DISPLAY 0.404255 (-4150 4850);
DISPLAY INVISIBLE (-4150 4850);
FORCEPROP 1 LAST MATERIAL CHIP
J 0
(-3750 4750);
DISPLAY 0.510638 (-3750 4750);
FORCEPROP 1 LAST WATTAGE 1/16W
J 2
(-3925 4800);
DISPLAY 0.404255 (-3925 4800);
FORCEPROP 1 LAST PACK_TYPE 0402LF
J 0
(-4150 4800);
DISPLAY 0.404255 (-4150 4800);
FORCEPROP 1 LAST VALUE 0
J 2
(-3900 4750);
DISPLAY 0.510638 (-3900 4750);
FORCEPROP 1 LAST TOLERANCE 5%
J 0
(-3825 4750);
DISPLAY 0.510638 (-3825 4750);
FORCEPROP 1 LAST $LOCATION R2676
J 0
(-4275 4750);
DISPLAY 0.638298 (-4275 4750);
FORCEPROP 1 LASTPIN (-4150 4750) $PN 1
J 0
(-4138 4762);
DISPLAY 0.787234 (-4138 4762);
PAINT MONO (-4138 4762);
FORCEPROP 1 LASTPIN (-3950 4750) $PN 2
J 0
(-3988 4762);
DISPLAY 0.787234 (-3988 4762);
PAINT MONO (-3988 4762);
FORCEPROP 2 LAST CDS_LIB pure_quanta
J 0
(-4050 4750);
DISPLAY INVISIBLE (-4050 4750);
FORCEPROP 1 LAST PATH I19
J 0
(-4100 4900);
DISPLAY 0.978723 (-4100 4900);
PAINT WHITE (-4100 4900);
DISPLAY INVISIBLE (-4100 4900);
FORCEPROP 0 LAST CDS_LOCATION R2676
J 0
(-3925 4850);
DISPLAY 1.021277 (-3925 4850);
DISPLAY INVISIBLE (-3925 4850);
FORCEPROP 0 LAST $SEC 1
J 0
(-3925 4850);
DISPLAY 0.680851 (-3925 4850);
PAINT MONO (-3925 4850);
DISPLAY INVISIBLE (-3925 4850);
FORCEPROP 0 LAST CDS_SEC 1
J 0
(-3925 4850);
DISPLAY 1.021277 (-3925 4850);
DISPLAY INVISIBLE (-3925 4850);
FORCEADD OFFPAGE..6
(-7050 6075);
FORCEPROP 2 LAST $XR1 241 
J 0
(-7450 6075);
DISPLAY 0.638298 (-7450 6075);
PAINT MONO (-7450 6075);
FORCEPROP 2 LAST $XR0 240 
J 0
(-7330 6075);
DISPLAY 0.638298 (-7330 6075);
PAINT MONO (-7330 6075);
FORCEPROP 2 LAST CDS_LIB standard
J 0
(-7050 6075);
PAINT MONO (-7050 6075);
DISPLAY INVISIBLE (-7050 6075);
FORCEPROP 1 LAST OFFPAGE TRUE
J 0
(-6725 5950);
DISPLAY 0.872340 (-6725 5950);
DISPLAY INVISIBLE (-6725 5950);
FORCEPROP 1 LAST COMMENT_BODY TRUE
J 0
(-6950 6000);
DISPLAY 0.872340 (-6950 6000);
PAINT GREEN (-6950 6000);
DISPLAY INVISIBLE (-6950 6000);
FORCEPROP 2 LAST PATH I2
J 0
(-7325 6125);
DISPLAY 1.021277 (-7325 6125);
DISPLAY INVISIBLE (-7325 6125);
FORCEADD Q_CAP..1
(-4125 6425);
FORCEPROP 1 LAST PART_NUMBER CH4104K1B00
J 0
(-4075 6275);
DISPLAY 0.510638 (-4075 6275);
DISPLAY INVISIBLE (-4075 6275);
FORCEPROP 1 LAST VALUE 0.1UF
J 0
(-4075 6475);
DISPLAY 0.510638 (-4075 6475);
FORCEPROP 1 LAST VOLTAGE 25V
J 0
(-4075 6425);
DISPLAY 0.510638 (-4075 6425);
FORCEPROP 1 LAST MATERIAL X7R
J 0
(-4075 6325);
DISPLAY 0.510638 (-4075 6325);
FORCEPROP 1 LAST PACK_TYPE 0402
J 0
(-4075 6225);
DISPLAY 0.510638 (-4075 6225);
FORCEPROP 1 LAST TOLERANCE 10%
J 0
(-4075 6375);
DISPLAY 0.510638 (-4075 6375);
FORCEPROP 1 LAST $LOCATION C1796
J 0
(-4075 6525);
DISPLAY 0.978723 (-4075 6525);
FORCEPROP 1 LASTPIN (-4125 6525) $PN 1
J 0
(-4115 6505);
DISPLAY 0.787234 (-4115 6505);
FORCEPROP 1 LASTPIN (-4125 6325) $PN 2
J 0
(-4115 6305);
DISPLAY 0.787234 (-4115 6305);
FORCEPROP 2 LAST CDS_LIB pure_quanta
J 0
(-4125 6425);
PAINT MONO (-4125 6425);
DISPLAY INVISIBLE (-4125 6425);
FORCEPROP 1 LAST PATH I20
J 0
(-4075 6575);
DISPLAY 0.978723 (-4075 6575);
PAINT WHITE (-4075 6575);
DISPLAY INVISIBLE (-4075 6575);
FORCEPROP 2 LAST CDS_LOCATION C1796
J 0
(-4075 6625);
DISPLAY 1.021277 (-4075 6625);
DISPLAY INVISIBLE (-4075 6625);
FORCEPROP 2 LAST $SEC 1
J 0
(-4075 6625);
DISPLAY 0.680851 (-4075 6625);
PAINT MONO (-4075 6625);
DISPLAY INVISIBLE (-4075 6625);
FORCEPROP 2 LAST CDS_SEC 1
J 0
(-4075 6625);
DISPLAY 1.021277 (-4075 6625);
DISPLAY INVISIBLE (-4075 6625);
FORCEADD UNIVERSAL_GND..1
(-4125 6200);
FORCEPROP 3 LASTPIN (-4125 6250) SIG_NAME GND\g
J 0
(-4115 6260);
DISPLAY 0.659574 (-4115 6260);
PAINT MONO (-4115 6260);
DISPLAY INVISIBLE (-4115 6260);
FORCEPROP 2 LAST CDS_LIB logical_power
J 0
(-4125 6200);
PAINT MONO (-4125 6200);
DISPLAY INVISIBLE (-4125 6200);
FORCEPROP 1 LAST HDL_POWER GND
J 1
(-4100 6125);
DISPLAY 0.872340 (-4100 6125);
PAINT GREEN (-4100 6125);
DISPLAY INVISIBLE (-4100 6125);
FORCEPROP 1 LAST PATH I21
J 0
(-4050 6200);
DISPLAY 0.872340 (-4050 6200);
PAINT AQUA (-4050 6200);
DISPLAY INVISIBLE (-4050 6200);
FORCEADD UNIVERSAL_POWER..1
(-4300 6725);
FORCEPROP 3 LASTPIN (-4300 6675) SIG_NAME P3V3_AUX\g
J 0
(-4290 6685);
DISPLAY 0.659574 (-4290 6685);
PAINT MONO (-4290 6685);
DISPLAY INVISIBLE (-4290 6685);
FORCEPROP 1 LAST HDL_POWER P3V3_AUX
J 1
(-4300 6825);
DISPLAY 0.872340 (-4300 6825);
PAINT GREEN (-4300 6825);
FORCEPROP 2 LAST CDS_LIB logical_power
J 0
(-4300 6725);
PAINT MONO (-4300 6725);
DISPLAY INVISIBLE (-4300 6725);
FORCEPROP 1 LAST PATH I22
J 0
(-4250 6750);
DISPLAY 0.872340 (-4250 6750);
PAINT AQUA (-4250 6750);
DISPLAY INVISIBLE (-4250 6750);
FORCEADD Q_RES..2
(-3375 6400);
FORCEPROP 1 LAST PART_NUMBER CS35492FB03
J 0
(-3335 6275);
DISPLAY 0.404255 (-3335 6275);
DISPLAY INVISIBLE (-3335 6275);
FORCEPROP 1 LAST PACK_TYPE 0402LF
J 0
(-3335 6225);
DISPLAY 0.404255 (-3335 6225);
FORCEPROP 1 LAST VALUE 54.9K
J 0
(-3330 6475);
DISPLAY 0.404255 (-3330 6475);
FORCEPROP 1 LAST TOLERANCE 1%
J 0
(-3330 6425);
DISPLAY 0.404255 (-3330 6425);
FORCEPROP 1 LAST WATTAGE 1/16W
J 0
(-3335 6375);
DISPLAY 0.404255 (-3335 6375);
FORCEPROP 1 LAST MATERIAL CHIP
J 0
(-3335 6325);
DISPLAY 0.404255 (-3335 6325);
FORCEPROP 1 LAST $LOCATION R3521
J 0
(-3330 6525);
DISPLAY 0.978723 (-3330 6525);
FORCEPROP 1 LASTPIN (-3375 6500) $PN 1
J 0
(-3370 6462);
DISPLAY 0.787234 (-3370 6462);
PAINT MONO (-3370 6462);
FORCEPROP 1 LASTPIN (-3375 6300) $PN 2
J 0
(-3370 6310);
DISPLAY 0.787234 (-3370 6310);
PAINT MONO (-3370 6310);
FORCEPROP 2 LAST CDS_LIB pure_quanta
J 0
(-3375 6400);
DISPLAY INVISIBLE (-3375 6400);
FORCEPROP 1 LAST PATH I23
J 0
(-3325 6575);
DISPLAY 0.978723 (-3325 6575);
PAINT WHITE (-3325 6575);
DISPLAY INVISIBLE (-3325 6575);
FORCEPROP 0 LAST CDS_LOCATION R3521
J 0
(-3325 6575);
DISPLAY 1.021277 (-3325 6575);
DISPLAY INVISIBLE (-3325 6575);
FORCEPROP 0 LAST $SEC 1
J 0
(-3325 6575);
DISPLAY 0.680851 (-3325 6575);
PAINT MONO (-3325 6575);
DISPLAY INVISIBLE (-3325 6575);
FORCEPROP 0 LAST CDS_SEC 1
J 0
(-3325 6575);
DISPLAY 1.021277 (-3325 6575);
DISPLAY INVISIBLE (-3325 6575);
FORCEADD UNIVERSAL_POWER..1
(-3375 6725);
FORCEPROP 3 LASTPIN (-3375 6675) SIG_NAME P3V3_AUX\g
J 0
(-3365 6685);
DISPLAY 0.659574 (-3365 6685);
PAINT MONO (-3365 6685);
DISPLAY INVISIBLE (-3365 6685);
FORCEPROP 1 LAST HDL_POWER P3V3_AUX
J 1
(-3375 6775);
DISPLAY 0.872340 (-3375 6775);
PAINT GREEN (-3375 6775);
FORCEPROP 2 LAST CDS_LIB logical_power
J 0
(-3375 6725);
PAINT MONO (-3375 6725);
DISPLAY INVISIBLE (-3375 6725);
FORCEPROP 1 LAST PATH I24
J 0
(-3325 6750);
DISPLAY 0.872340 (-3325 6750);
PAINT AQUA (-3325 6750);
DISPLAY INVISIBLE (-3325 6750);
FORCEADD Q_RES..2
(-3125 6400);
FORCEPROP 1 LAST PART_NUMBER CS35492FB03
J 0
(-3085 6275);
DISPLAY 0.404255 (-3085 6275);
DISPLAY INVISIBLE (-3085 6275);
FORCEPROP 1 LAST PACK_TYPE 0402LF
J 0
(-3085 6225);
DISPLAY 0.404255 (-3085 6225);
FORCEPROP 1 LAST VALUE 54.9K
J 0
(-3080 6475);
DISPLAY 0.404255 (-3080 6475);
FORCEPROP 1 LAST TOLERANCE 1%
J 0
(-3080 6425);
DISPLAY 0.404255 (-3080 6425);
FORCEPROP 1 LAST WATTAGE 1/16W
J 0
(-3085 6375);
DISPLAY 0.404255 (-3085 6375);
FORCEPROP 1 LAST MATERIAL CHIP
J 0
(-3085 6325);
DISPLAY 0.404255 (-3085 6325);
FORCEPROP 1 LAST $LOCATION R3522
J 0
(-3080 6525);
DISPLAY 0.978723 (-3080 6525);
FORCEPROP 1 LASTPIN (-3125 6500) $PN 1
J 0
(-3120 6462);
DISPLAY 0.787234 (-3120 6462);
PAINT MONO (-3120 6462);
FORCEPROP 1 LASTPIN (-3125 6300) $PN 2
J 0
(-3120 6310);
DISPLAY 0.787234 (-3120 6310);
PAINT MONO (-3120 6310);
FORCEPROP 2 LAST CDS_LIB pure_quanta
J 0
(-3125 6400);
DISPLAY INVISIBLE (-3125 6400);
FORCEPROP 1 LAST PATH I25
J 0
(-3075 6575);
DISPLAY 0.978723 (-3075 6575);
PAINT WHITE (-3075 6575);
DISPLAY INVISIBLE (-3075 6575);
FORCEPROP 0 LAST CDS_LOCATION R3522
J 0
(-3075 6575);
DISPLAY 1.021277 (-3075 6575);
DISPLAY INVISIBLE (-3075 6575);
FORCEPROP 0 LAST $SEC 1
J 0
(-3075 6575);
DISPLAY 0.680851 (-3075 6575);
PAINT MONO (-3075 6575);
DISPLAY INVISIBLE (-3075 6575);
FORCEPROP 0 LAST CDS_SEC 1
J 0
(-3075 6575);
DISPLAY 1.021277 (-3075 6575);
DISPLAY INVISIBLE (-3075 6575);
FORCEADD Q_RES..1
(-2825 6075);
FORCEPROP 1 LAST PART_NUMBER CS03322FB03
J 0
(-2950 6125);
DISPLAY 0.404255 (-2950 6125);
DISPLAY INVISIBLE (-2950 6125);
FORCEPROP 1 LAST WATTAGE 1/16W
J 2
(-2725 6175);
DISPLAY 0.404255 (-2725 6175);
FORCEPROP 1 LAST PACK_TYPE 0402LF
J 0
(-2950 6175);
DISPLAY 0.404255 (-2950 6175);
FORCEPROP 1 LAST TOLERANCE 1%
J 0
(-2600 6075);
DISPLAY 0.510638 (-2600 6075);
FORCEPROP 1 LAST VALUE 33.2
J 2
(-2625 6075);
DISPLAY 0.510638 (-2625 6075);
FORCEPROP 1 LAST MATERIAL CHIP
J 0
(-2525 6075);
DISPLAY 0.510638 (-2525 6075);
FORCEPROP 1 LAST $LOCATION R2990
J 0
(-3050 6075);
DISPLAY 0.638298 (-3050 6075);
FORCEPROP 1 LASTPIN (-2925 6075) $PN 1
J 0
(-2913 6087);
DISPLAY 0.787234 (-2913 6087);
PAINT MONO (-2913 6087);
FORCEPROP 1 LASTPIN (-2725 6075) $PN 2
J 0
(-2763 6087);
DISPLAY 0.787234 (-2763 6087);
PAINT MONO (-2763 6087);
FORCEPROP 2 LAST CDS_LIB pure_quanta
J 0
(-2825 6075);
DISPLAY INVISIBLE (-2825 6075);
FORCEPROP 1 LAST PATH I26
J 0
(-2875 6225);
DISPLAY 0.978723 (-2875 6225);
PAINT WHITE (-2875 6225);
DISPLAY INVISIBLE (-2875 6225);
FORCEPROP 0 LAST CDS_LOCATION R2990
J 0
(-2725 6200);
DISPLAY 1.021277 (-2725 6200);
DISPLAY INVISIBLE (-2725 6200);
FORCEPROP 0 LAST $SEC 1
J 0
(-2725 6200);
DISPLAY 0.680851 (-2725 6200);
PAINT MONO (-2725 6200);
DISPLAY INVISIBLE (-2725 6200);
FORCEPROP 0 LAST CDS_SEC 1
J 0
(-2725 6200);
DISPLAY 1.021277 (-2725 6200);
DISPLAY INVISIBLE (-2725 6200);
FORCEADD Q_RES..1
(-2825 5975);
FORCEPROP 1 LAST PART_NUMBER CS03322FB03
J 0
(-2950 6025);
DISPLAY 0.404255 (-2950 6025);
DISPLAY INVISIBLE (-2950 6025);
FORCEPROP 1 LAST VALUE 33.2
J 2
(-2625 5975);
DISPLAY 0.510638 (-2625 5975);
FORCEPROP 1 LAST TOLERANCE 1%
J 0
(-2600 5975);
DISPLAY 0.510638 (-2600 5975);
FORCEPROP 1 LAST MATERIAL CHIP
J 0
(-2525 5975);
DISPLAY 0.510638 (-2525 5975);
FORCEPROP 1 LAST $LOCATION R2991
J 0
(-3050 5975);
DISPLAY 0.638298 (-3050 5975);
FORCEPROP 1 LASTPIN (-2925 5975) $PN 1
J 0
(-2913 5987);
DISPLAY 0.787234 (-2913 5987);
PAINT MONO (-2913 5987);
FORCEPROP 1 LASTPIN (-2725 5975) $PN 2
J 0
(-2763 5987);
DISPLAY 0.787234 (-2763 5987);
PAINT MONO (-2763 5987);
FORCEPROP 2 LAST CDS_LIB pure_quanta
J 0
(-2825 5975);
DISPLAY INVISIBLE (-2825 5975);
FORCEPROP 1 LAST PACK_TYPE 0402LF
J 0
(-2950 6075);
DISPLAY 0.404255 (-2950 6075);
DISPLAY INVISIBLE (-2950 6075);
FORCEPROP 1 LAST WATTAGE 1/16W
J 2
(-2725 6075);
DISPLAY 0.404255 (-2725 6075);
DISPLAY INVISIBLE (-2725 6075);
FORCEPROP 1 LAST PATH I27
J 0
(-2875 6125);
DISPLAY 0.978723 (-2875 6125);
PAINT WHITE (-2875 6125);
DISPLAY INVISIBLE (-2875 6125);
FORCEPROP 0 LAST CDS_LOCATION R2991
J 0
(-3050 6025);
DISPLAY 1.021277 (-3050 6025);
DISPLAY INVISIBLE (-3050 6025);
FORCEPROP 0 LAST $SEC 1
J 0
(-3050 6025);
DISPLAY 0.680851 (-3050 6025);
PAINT MONO (-3050 6025);
DISPLAY INVISIBLE (-3050 6025);
FORCEPROP 0 LAST CDS_SEC 1
J 0
(-3050 6025);
DISPLAY 1.021277 (-3050 6025);
DISPLAY INVISIBLE (-3050 6025);
FORCEADD UNIVERSAL_GND..1
(-2825 4325);
FORCEPROP 3 LASTPIN (-2825 4375) SIG_NAME GND\g
J 0
(-2815 4385);
DISPLAY 0.659574 (-2815 4385);
PAINT MONO (-2815 4385);
DISPLAY INVISIBLE (-2815 4385);
FORCEPROP 2 LAST CDS_LIB logical_power
J 0
(-2825 4325);
DISPLAY INVISIBLE (-2825 4325);
FORCEPROP 1 LAST HDL_POWER GND
J 1
(-2800 4250);
DISPLAY 0.872340 (-2800 4250);
PAINT GREEN (-2800 4250);
DISPLAY INVISIBLE (-2800 4250);
FORCEPROP 1 LAST PATH I28
J 0
(-2750 4325);
DISPLAY 0.872340 (-2750 4325);
PAINT AQUA (-2750 4325);
DISPLAY INVISIBLE (-2750 4325);
FORCEADD Q_RES..1
(-2325 3825);
FORCEPROP 1 LAST PART_NUMBER CS00002JB13
J 0
(-2425 3775);
DISPLAY 0.404255 (-2425 3775);
DISPLAY INVISIBLE (-2425 3775);
FORCEPROP 1 LAST MATERIAL CHIP
J 0
(-2025 3825);
DISPLAY 0.510638 (-2025 3825);
FORCEPROP 1 LAST PACK_TYPE 0402LF
J 0
(-2425 3725);
DISPLAY 0.404255 (-2425 3725);
FORCEPROP 1 LAST VALUE 0
J 2
(-2175 3825);
DISPLAY 0.510638 (-2175 3825);
FORCEPROP 1 LAST WATTAGE 1/16W
J 2
(-2200 3725);
DISPLAY 0.404255 (-2200 3725);
FORCEPROP 1 LAST TOLERANCE 5%
J 0
(-2100 3825);
DISPLAY 0.510638 (-2100 3825);
FORCEPROP 1 LAST $LOCATION R2725
J 0
(-2525 3825);
DISPLAY 0.638298 (-2525 3825);
FORCEPROP 1 LASTPIN (-2425 3825) $PN 1
J 0
(-2413 3837);
DISPLAY 0.787234 (-2413 3837);
PAINT MONO (-2413 3837);
FORCEPROP 1 LASTPIN (-2225 3825) $PN 2
J 0
(-2263 3837);
DISPLAY 0.787234 (-2263 3837);
PAINT MONO (-2263 3837);
FORCEPROP 2 LAST CDS_LIB pure_quanta
J 0
(-2325 3825);
DISPLAY INVISIBLE (-2325 3825);
FORCEPROP 1 LAST PATH I29
J 0
(-2375 3975);
DISPLAY 0.978723 (-2375 3975);
PAINT WHITE (-2375 3975);
DISPLAY INVISIBLE (-2375 3975);
FORCEPROP 2 LAST CDS_LOCATION R2725
J 0
(-2375 4025);
DISPLAY 1.021277 (-2375 4025);
DISPLAY INVISIBLE (-2375 4025);
FORCEPROP 2 LAST $SEC 1
J 0
(-2375 4025);
DISPLAY 0.680851 (-2375 4025);
PAINT MONO (-2375 4025);
DISPLAY INVISIBLE (-2375 4025);
FORCEPROP 2 LAST CDS_SEC 1
J 0
(-2375 4025);
DISPLAY 1.021277 (-2375 4025);
DISPLAY INVISIBLE (-2375 4025);
FORCEADD OFFPAGE..4
R 2
(-7050 6175);
FORCEPROP 2 LAST $XR1 234 
J 0
(-7422 6175);
DISPLAY 0.638298 (-7422 6175);
PAINT MONO (-7422 6175);
FORCEPROP 2 LAST $XR0 213 
J 0
(-7302 6175);
DISPLAY 0.638298 (-7302 6175);
PAINT MONO (-7302 6175);
FORCEPROP 2 LAST CDS_LIB standard
J 0
(-7050 6175);
DISPLAY INVISIBLE (-7050 6175);
FORCEPROP 1 LAST OFFPAGE TRUE
J 2
(-7375 6050);
DISPLAY 0.872340 (-7375 6050);
DISPLAY INVISIBLE (-7375 6050);
FORCEPROP 1 LAST COMMENT_BODY TRUE
J 2
(-7025 6075);
DISPLAY 0.872340 (-7025 6075);
PAINT GREEN (-7025 6075);
DISPLAY INVISIBLE (-7025 6075);
FORCEPROP 2 LAST PATH I3
J 0
(-7300 6225);
DISPLAY 1.021277 (-7300 6225);
DISPLAY INVISIBLE (-7300 6225);
FORCEADD Q_RES..1
(-2325 3900);
FORCEPROP 1 LAST PART_NUMBER CS00002JB13
J 0
(-2425 3850);
DISPLAY 0.404255 (-2425 3850);
DISPLAY INVISIBLE (-2425 3850);
FORCEPROP 1 LAST VALUE 0
J 2
(-2175 3900);
DISPLAY 0.510638 (-2175 3900);
FORCEPROP 1 LAST MATERIAL CHIP
J 0
(-2025 3900);
DISPLAY 0.510638 (-2025 3900);
FORCEPROP 1 LAST $LOCATION R2706
J 0
(-2525 3900);
DISPLAY 0.638298 (-2525 3900);
FORCEPROP 1 LASTPIN (-2425 3900) $PN 1
J 0
(-2413 3912);
DISPLAY 0.787234 (-2413 3912);
PAINT MONO (-2413 3912);
FORCEPROP 1 LASTPIN (-2225 3900) $PN 2
J 0
(-2263 3912);
DISPLAY 0.787234 (-2263 3912);
PAINT MONO (-2263 3912);
FORCEPROP 1 LAST WATTAGE 1/16W
J 2
(-2200 3800);
DISPLAY 0.404255 (-2200 3800);
DISPLAY INVISIBLE (-2200 3800);
FORCEPROP 1 LAST TOLERANCE 5%
J 0
(-2100 3900);
DISPLAY 0.510638 (-2100 3900);
DISPLAY INVISIBLE (-2100 3900);
FORCEPROP 1 LAST PACK_TYPE 0402LF
J 0
(-2425 3800);
DISPLAY 0.404255 (-2425 3800);
DISPLAY INVISIBLE (-2425 3800);
FORCEPROP 2 LAST CDS_LIB pure_quanta
J 0
(-2325 3900);
DISPLAY INVISIBLE (-2325 3900);
FORCEPROP 1 LAST PATH I30
J 0
(-2375 4050);
DISPLAY 0.978723 (-2375 4050);
PAINT WHITE (-2375 4050);
DISPLAY INVISIBLE (-2375 4050);
FORCEPROP 0 LAST CDS_LOCATION R2706
J 0
(-2200 4000);
DISPLAY 1.021277 (-2200 4000);
DISPLAY INVISIBLE (-2200 4000);
FORCEPROP 0 LAST $SEC 1
J 0
(-2200 4000);
DISPLAY 0.680851 (-2200 4000);
PAINT MONO (-2200 4000);
DISPLAY INVISIBLE (-2200 4000);
FORCEPROP 0 LAST CDS_SEC 1
J 0
(-2200 4000);
DISPLAY 1.021277 (-2200 4000);
DISPLAY INVISIBLE (-2200 4000);
FORCEADD LTC4307CMS8..1
(-2275 4600);
FORCEPROP 1 LAST PART_NUMBER AL004307000
J 0
(-2525 4860);
DISPLAY 0.723404 (-2525 4860);
PAINT GREEN (-2525 4860);
DISPLAY INVISIBLE (-2525 4860);
FORCEPROP 2 LAST VALUE LTC4307CMS8
J 0
(-2525 4950);
DISPLAY 1.021277 (-2525 4950);
FORCEPROP 2 LAST PART_TYPE SMLF
J 0
(-2525 5000);
DISPLAY 1.021277 (-2525 5000);
FORCEPROP 1 LAST MATERIAL EMPTY
J 0
(-2525 4810);
DISPLAY 0.723404 (-2525 4810);
PAINT RED (-2525 4810);
FORCEPROP 1 LAST LOCATION U176
J 0
(-2525 4905);
DISPLAY 0.723404 (-2525 4905);
PAINT GREEN (-2525 4905);
FORCEPROP 0 LASTPIN (-2675 4750) $PN 1
J 2
(-2685 4760);
DISPLAY 0.680851 (-2685 4760);
PAINT MONO (-2685 4760);
FORCEPROP 0 LASTPIN (-2675 4450) $PN 4
J 2
(-2685 4460);
DISPLAY 0.680851 (-2685 4460);
PAINT MONO (-2685 4460);
FORCEPROP 0 LASTPIN (-1875 4450) $PN 5
J 0
(-1865 4460);
DISPLAY 0.680851 (-1865 4460);
PAINT MONO (-1865 4460);
FORCEPROP 0 LASTPIN (-2675 4650) $PN 3
J 2
(-2685 4660);
DISPLAY 0.680851 (-2685 4660);
PAINT MONO (-2685 4660);
FORCEPROP 0 LASTPIN (-1875 4650) $PN 2
J 0
(-1865 4660);
DISPLAY 0.680851 (-1865 4660);
PAINT MONO (-1865 4660);
FORCEPROP 0 LASTPIN (-2675 4550) $PN 6
J 2
(-2685 4560);
DISPLAY 0.680851 (-2685 4560);
PAINT MONO (-2685 4560);
FORCEPROP 0 LASTPIN (-1875 4550) $PN 7
J 0
(-1865 4560);
DISPLAY 0.680851 (-1865 4560);
PAINT MONO (-1865 4560);
FORCEPROP 0 LASTPIN (-1875 4750) $PN 8
J 0
(-1865 4760);
DISPLAY 0.680851 (-1865 4760);
PAINT MONO (-1865 4760);
FORCEPROP 1 LAST NEEDS_NO_SIZE TRUE
J 0
(-2275 4600);
DISPLAY 0.468085 (-2275 4600);
PAINT GREEN (-2275 4600);
DISPLAY INVISIBLE (-2275 4600);
FORCEPROP 2 LAST CDS_LIB pure_quanta
J 0
(-2275 4600);
DISPLAY INVISIBLE (-2275 4600);
FORCEPROP 1 LAST PATH I31
J 0
(-2050 4805);
DISPLAY 0.723404 (-2050 4805);
PAINT GREEN (-2050 4805);
DISPLAY INVISIBLE (-2050 4805);
FORCEPROP 0 LAST $SEC 1
J 0
(-2525 5050);
DISPLAY 0.680851 (-2525 5050);
PAINT MONO (-2525 5050);
DISPLAY INVISIBLE (-2525 5050);
FORCEPROP 0 LAST CDS_SEC 1
J 0
(-2525 5050);
DISPLAY 1.021277 (-2525 5050);
DISPLAY INVISIBLE (-2525 5050);
FORCEADD UNIVERSAL_GND..1
(-1625 4825);
FORCEPROP 3 LASTPIN (-1625 4875) SIG_NAME GND\g
J 0
(-1615 4885);
DISPLAY 0.659574 (-1615 4885);
PAINT MONO (-1615 4885);
DISPLAY INVISIBLE (-1615 4885);
FORCEPROP 2 LAST CDS_LIB logical_power
J 0
(-1625 4825);
PAINT MONO (-1625 4825);
DISPLAY INVISIBLE (-1625 4825);
FORCEPROP 1 LAST HDL_POWER GND
J 1
(-1600 4750);
DISPLAY 0.872340 (-1600 4750);
PAINT GREEN (-1600 4750);
DISPLAY INVISIBLE (-1600 4750);
FORCEPROP 1 LAST PATH I32
J 0
(-1550 4825);
DISPLAY 0.872340 (-1550 4825);
PAINT AQUA (-1550 4825);
DISPLAY INVISIBLE (-1550 4825);
FORCEADD Q_RES..1
(-2275 6900);
FORCEPROP 1 LAST PART_NUMBER CS00002JB13
J 0
(-2375 6850);
DISPLAY 0.404255 (-2375 6850);
DISPLAY INVISIBLE (-2375 6850);
FORCEPROP 1 LAST VALUE 0
J 2
(-2125 6900);
DISPLAY 0.510638 (-2125 6900);
FORCEPROP 1 LAST PACK_TYPE 0402LF
J 0
(-2375 6800);
DISPLAY 0.404255 (-2375 6800);
FORCEPROP 1 LAST MATERIAL EMPTY
J 0
(-1975 6900);
DISPLAY 0.510638 (-1975 6900);
PAINT RED (-1975 6900);
FORCEPROP 1 LAST TOLERANCE 5%
J 0
(-2050 6900);
DISPLAY 0.510638 (-2050 6900);
FORCEPROP 1 LAST WATTAGE 1/16W
J 2
(-2150 6800);
DISPLAY 0.404255 (-2150 6800);
FORCEPROP 1 LAST $LOCATION R2894
J 0
(-2450 6900);
DISPLAY 0.638298 (-2450 6900);
FORCEPROP 1 LASTPIN (-2375 6900) $PN 1
J 0
(-2363 6912);
DISPLAY 0.787234 (-2363 6912);
PAINT MONO (-2363 6912);
FORCEPROP 1 LASTPIN (-2175 6900) $PN 2
J 0
(-2213 6912);
DISPLAY 0.787234 (-2213 6912);
PAINT MONO (-2213 6912);
FORCEPROP 2 LAST CDS_LIB pure_quanta
J 0
(-2275 6900);
DISPLAY INVISIBLE (-2275 6900);
FORCEPROP 1 LAST PATH I33
J 0
(-2325 7050);
DISPLAY 0.978723 (-2325 7050);
PAINT WHITE (-2325 7050);
DISPLAY INVISIBLE (-2325 7050);
FORCEPROP 2 LAST CDS_LOCATION R2894
J 0
(-2325 7100);
DISPLAY 1.021277 (-2325 7100);
DISPLAY INVISIBLE (-2325 7100);
FORCEPROP 2 LAST $SEC 1
J 0
(-2325 7100);
DISPLAY 0.680851 (-2325 7100);
PAINT MONO (-2325 7100);
DISPLAY INVISIBLE (-2325 7100);
FORCEPROP 2 LAST CDS_SEC 1
J 0
(-2325 7100);
DISPLAY 1.021277 (-2325 7100);
DISPLAY INVISIBLE (-2325 7100);
FORCEADD Q_CAP..1
(-1625 5050);
FORCEPROP 1 LAST PART_NUMBER CH4104K1B00
J 0
(-1575 4900);
DISPLAY 0.510638 (-1575 4900);
DISPLAY INVISIBLE (-1575 4900);
FORCEPROP 1 LAST PACK_TYPE 0402
J 0
(-1575 4850);
DISPLAY 0.510638 (-1575 4850);
FORCEPROP 1 LAST VALUE 0.1UF
J 0
(-1575 5100);
DISPLAY 0.510638 (-1575 5100);
FORCEPROP 1 LAST VOLTAGE 25V
J 0
(-1575 5050);
DISPLAY 0.510638 (-1575 5050);
FORCEPROP 1 LAST TOLERANCE 10%
J 0
(-1575 5000);
DISPLAY 0.510638 (-1575 5000);
FORCEPROP 1 LAST MATERIAL EMPTY
J 0
(-1575 4950);
DISPLAY 0.510638 (-1575 4950);
FORCEPROP 1 LAST $LOCATION C1708
J 0
(-1575 5150);
DISPLAY 0.978723 (-1575 5150);
FORCEPROP 1 LASTPIN (-1625 5150) $PN 1
J 0
(-1615 5130);
DISPLAY 0.787234 (-1615 5130);
FORCEPROP 1 LASTPIN (-1625 4950) $PN 2
J 0
(-1615 4930);
DISPLAY 0.787234 (-1615 4930);
FORCEPROP 2 LAST CDS_LIB pure_quanta
J 0
(-1625 5050);
PAINT MONO (-1625 5050);
DISPLAY INVISIBLE (-1625 5050);
FORCEPROP 1 LAST PATH I34
J 0
(-1575 5200);
DISPLAY 0.978723 (-1575 5200);
PAINT WHITE (-1575 5200);
DISPLAY INVISIBLE (-1575 5200);
FORCEPROP 2 LAST CDS_LOCATION C1708
J 0
(-1575 5250);
DISPLAY 1.021277 (-1575 5250);
DISPLAY INVISIBLE (-1575 5250);
FORCEPROP 2 LAST $SEC 1
J 0
(-1575 5250);
DISPLAY 0.680851 (-1575 5250);
PAINT MONO (-1575 5250);
DISPLAY INVISIBLE (-1575 5250);
FORCEPROP 2 LAST CDS_SEC 1
J 0
(-1575 5250);
DISPLAY 1.021277 (-1575 5250);
DISPLAY INVISIBLE (-1575 5250);
FORCEADD UNIVERSAL_POWER..1
(-1800 5350);
FORCEPROP 3 LASTPIN (-1800 5300) SIG_NAME P3V3_AUX\g
J 0
(-1790 5310);
DISPLAY 0.659574 (-1790 5310);
PAINT MONO (-1790 5310);
DISPLAY INVISIBLE (-1790 5310);
FORCEPROP 1 LAST HDL_POWER P3V3_AUX
J 1
(-1800 5400);
DISPLAY 0.872340 (-1800 5400);
PAINT GREEN (-1800 5400);
FORCEPROP 2 LAST CDS_LIB logical_power
J 0
(-1800 5350);
PAINT MONO (-1800 5350);
DISPLAY INVISIBLE (-1800 5350);
FORCEPROP 1 LAST PATH I35
J 0
(-1750 5375);
DISPLAY 0.872340 (-1750 5375);
PAINT AQUA (-1750 5375);
DISPLAY INVISIBLE (-1750 5375);
FORCEADD OFFPAGE..2
(-1500 5975);
FORCEPROP 2 LAST $XR0 143 
J 0
(-1311 5975);
DISPLAY 0.638298 (-1311 5975);
PAINT MONO (-1311 5975);
FORCEPROP 2 LAST CDS_LIB standard
J 0
(-1500 5975);
DISPLAY INVISIBLE (-1500 5975);
FORCEPROP 1 LAST OFFPAGE TRUE
J 0
(-1175 5850);
DISPLAY 0.872340 (-1175 5850);
PAINT GREEN (-1175 5850);
DISPLAY INVISIBLE (-1175 5850);
FORCEPROP 1 LAST COMMENT_BODY TRUE
J 0
(-1545 5880);
DISPLAY 0.872340 (-1545 5880);
PAINT GREEN (-1545 5880);
DISPLAY INVISIBLE (-1545 5880);
FORCEPROP 2 LAST PATH I36
J 0
(-1300 6025);
DISPLAY 1.021277 (-1300 6025);
DISPLAY INVISIBLE (-1300 6025);
FORCEADD OFFPAGE..3
(-1500 6075);
FORCEPROP 2 LAST $XR0 143 
J 0
(-1286 6075);
DISPLAY 0.638298 (-1286 6075);
PAINT MONO (-1286 6075);
FORCEPROP 2 LAST CDS_LIB standard
J 0
(-1500 6075);
PAINT MONO (-1500 6075);
DISPLAY INVISIBLE (-1500 6075);
FORCEPROP 1 LAST OFFPAGE TRUE
J 0
(-1175 5950);
DISPLAY 0.872340 (-1175 5950);
PAINT GREEN (-1175 5950);
DISPLAY INVISIBLE (-1175 5950);
FORCEPROP 1 LAST COMMENT_BODY TRUE
J 0
(-1550 5975);
DISPLAY 0.872340 (-1550 5975);
PAINT GREEN (-1550 5975);
DISPLAY INVISIBLE (-1550 5975);
FORCEPROP 2 LAST PATH I37
J 0
(-1275 6125);
DISPLAY 1.021277 (-1275 6125);
DISPLAY INVISIBLE (-1275 6125);
FORCEADD Q_RES..1
(-2275 6975);
FORCEPROP 1 LAST PART_NUMBER CS00002JB13
J 0
(-2375 6925);
DISPLAY 0.404255 (-2375 6925);
DISPLAY INVISIBLE (-2375 6925);
FORCEPROP 1 LAST MATERIAL EMPTY
J 0
(-1975 6975);
DISPLAY 0.510638 (-1975 6975);
PAINT RED (-1975 6975);
FORCEPROP 1 LAST VALUE 0
J 2
(-2125 6975);
DISPLAY 0.510638 (-2125 6975);
FORCEPROP 1 LAST $LOCATION R2893
J 0
(-2450 6975);
DISPLAY 0.638298 (-2450 6975);
FORCEPROP 1 LASTPIN (-2375 6975) $PN 1
J 0
(-2363 6987);
DISPLAY 0.787234 (-2363 6987);
PAINT MONO (-2363 6987);
FORCEPROP 1 LASTPIN (-2175 6975) $PN 2
J 0
(-2213 6987);
DISPLAY 0.787234 (-2213 6987);
PAINT MONO (-2213 6987);
FORCEPROP 2 LAST CDS_LIB pure_quanta
J 0
(-2275 6975);
DISPLAY INVISIBLE (-2275 6975);
FORCEPROP 1 LAST PACK_TYPE 0402LF
J 0
(-2375 6875);
DISPLAY 0.404255 (-2375 6875);
DISPLAY INVISIBLE (-2375 6875);
FORCEPROP 1 LAST TOLERANCE 5%
J 0
(-2050 6975);
DISPLAY 0.510638 (-2050 6975);
DISPLAY INVISIBLE (-2050 6975);
FORCEPROP 1 LAST WATTAGE 1/16W
J 2
(-2150 6875);
DISPLAY 0.404255 (-2150 6875);
DISPLAY INVISIBLE (-2150 6875);
FORCEPROP 1 LAST PATH I38
J 0
(-2325 7125);
DISPLAY 0.978723 (-2325 7125);
PAINT WHITE (-2325 7125);
DISPLAY INVISIBLE (-2325 7125);
FORCEPROP 0 LAST CDS_LOCATION R2893
J 0
(-2150 7075);
DISPLAY 1.021277 (-2150 7075);
DISPLAY INVISIBLE (-2150 7075);
FORCEPROP 0 LAST $SEC 1
J 0
(-2150 7075);
DISPLAY 0.680851 (-2150 7075);
PAINT MONO (-2150 7075);
DISPLAY INVISIBLE (-2150 7075);
FORCEPROP 0 LAST CDS_SEC 1
J 0
(-2150 7075);
DISPLAY 1.021277 (-2150 7075);
DISPLAY INVISIBLE (-2150 7075);
FORCEADD OFFPAGE..1
(-6975 8700);
FORCEPROP 2 LAST $XR0 231 
J 0
(-7257 8700);
DISPLAY 0.638298 (-7257 8700);
PAINT MONO (-7257 8700);
FORCEPROP 2 LAST CDS_LIB standard
J 0
(-6975 8700);
PAINT MONO (-6975 8700);
DISPLAY INVISIBLE (-6975 8700);
FORCEPROP 1 LAST OFFPAGE TRUE
J 0
(-6650 8575);
DISPLAY 0.872340 (-6650 8575);
DISPLAY INVISIBLE (-6650 8575);
FORCEPROP 1 LAST COMMENT_BODY TRUE
J 0
(-6850 8600);
DISPLAY 0.872340 (-6850 8600);
PAINT GREEN (-6850 8600);
DISPLAY INVISIBLE (-6850 8600);
FORCEPROP 2 LAST PATH I39
J 0
(-7250 8750);
DISPLAY 1.021277 (-7250 8750);
DISPLAY INVISIBLE (-7250 8750);
FORCEADD OFFPAGE..6
(-4950 4550);
FORCEPROP 2 LAST $XR1 241 
J 0
(-5380 4550);
DISPLAY 0.638298 (-5380 4550);
PAINT MONO (-5380 4550);
FORCEPROP 2 LAST $XR0 240 
J 0
(-5260 4550);
DISPLAY 0.638298 (-5260 4550);
PAINT MONO (-5260 4550);
FORCEPROP 2 LAST CDS_LIB standard
J 0
(-4950 4550);
PAINT MONO (-4950 4550);
DISPLAY INVISIBLE (-4950 4550);
FORCEPROP 1 LAST OFFPAGE TRUE
J 0
(-4625 4425);
DISPLAY 0.872340 (-4625 4425);
DISPLAY INVISIBLE (-4625 4425);
FORCEPROP 1 LAST COMMENT_BODY TRUE
J 0
(-4850 4475);
DISPLAY 0.872340 (-4850 4475);
PAINT GREEN (-4850 4475);
DISPLAY INVISIBLE (-4850 4475);
FORCEPROP 2 LAST PATH I4
J 0
(-5250 4600);
DISPLAY 1.021277 (-5250 4600);
DISPLAY INVISIBLE (-5250 4600);
FORCEADD OFFPAGE..6
(-6975 8800);
FORCEPROP 2 LAST $XR0 231 
J 0
(-7285 8800);
DISPLAY 0.638298 (-7285 8800);
PAINT MONO (-7285 8800);
FORCEPROP 2 LAST CDS_LIB standard
J 0
(-6975 8800);
PAINT MONO (-6975 8800);
DISPLAY INVISIBLE (-6975 8800);
FORCEPROP 1 LAST OFFPAGE TRUE
J 0
(-6650 8675);
DISPLAY 0.872340 (-6650 8675);
DISPLAY INVISIBLE (-6650 8675);
FORCEPROP 1 LAST COMMENT_BODY TRUE
J 0
(-6875 8725);
DISPLAY 0.872340 (-6875 8725);
PAINT GREEN (-6875 8725);
DISPLAY INVISIBLE (-6875 8725);
FORCEPROP 2 LAST PATH I40
J 0
(-7275 8850);
DISPLAY 1.021277 (-7275 8850);
DISPLAY INVISIBLE (-7275 8850);
FORCEADD OFFPAGE..4
R 2
(-6975 8900);
FORCEPROP 2 LAST $XR1 234 
J 0
(-7377 8900);
DISPLAY 0.638298 (-7377 8900);
PAINT MONO (-7377 8900);
FORCEPROP 2 LAST $XR0 213 
J 0
(-7257 8900);
DISPLAY 0.638298 (-7257 8900);
PAINT MONO (-7257 8900);
FORCEPROP 2 LAST CDS_LIB standard
J 0
(-6975 8900);
DISPLAY INVISIBLE (-6975 8900);
FORCEPROP 1 LAST OFFPAGE TRUE
J 2
(-7300 8775);
DISPLAY 0.872340 (-7300 8775);
DISPLAY INVISIBLE (-7300 8775);
FORCEPROP 1 LAST COMMENT_BODY TRUE
J 2
(-6950 8800);
DISPLAY 0.872340 (-6950 8800);
PAINT GREEN (-6950 8800);
DISPLAY INVISIBLE (-6950 8800);
FORCEPROP 2 LAST PATH I41
J 0
(-7250 8950);
DISPLAY 1.021277 (-7250 8950);
DISPLAY INVISIBLE (-7250 8950);
FORCEADD Q_RES..1
(-6125 8700);
FORCEPROP 1 LAST PART_NUMBER CS00002JB13
J 0
(-6200 8600);
DISPLAY 0.404255 (-6200 8600);
DISPLAY INVISIBLE (-6200 8600);
FORCEPROP 1 LAST PACK_TYPE 0402LF
J 0
(-6200 8650);
DISPLAY 0.404255 (-6200 8650);
FORCEPROP 1 LAST MATERIAL CHIP
J 0
(-5875 8700);
DISPLAY 0.510638 (-5875 8700);
FORCEPROP 1 LAST TOLERANCE 5%
J 0
(-5925 8700);
DISPLAY 0.510638 (-5925 8700);
FORCEPROP 1 LAST VALUE 0
J 2
(-5975 8700);
DISPLAY 0.510638 (-5975 8700);
FORCEPROP 1 LAST WATTAGE 1/16W
J 2
(-5975 8650);
DISPLAY 0.404255 (-5975 8650);
FORCEPROP 1 LAST $LOCATION R3106
J 0
(-6300 8675);
DISPLAY 0.510638 (-6300 8675);
FORCEPROP 1 LASTPIN (-6225 8700) $PN 1
J 0
(-6213 8712);
DISPLAY 0.787234 (-6213 8712);
PAINT MONO (-6213 8712);
FORCEPROP 1 LASTPIN (-6025 8700) $PN 2
J 0
(-6063 8712);
DISPLAY 0.787234 (-6063 8712);
PAINT MONO (-6063 8712);
FORCEPROP 2 LAST CDS_LIB pure_quanta
J 0
(-6125 8700);
DISPLAY INVISIBLE (-6125 8700);
FORCEPROP 1 LAST PATH I42
J 0
(-6175 8850);
DISPLAY 0.978723 (-6175 8850);
PAINT WHITE (-6175 8850);
DISPLAY INVISIBLE (-6175 8850);
FORCEPROP 0 LAST CDS_LOCATION R3106
J 0
(-6250 8750);
DISPLAY 1.021277 (-6250 8750);
DISPLAY INVISIBLE (-6250 8750);
FORCEPROP 0 LAST $SEC 1
J 0
(-6250 8750);
DISPLAY 0.680851 (-6250 8750);
PAINT MONO (-6250 8750);
DISPLAY INVISIBLE (-6250 8750);
FORCEPROP 0 LAST CDS_SEC 1
J 0
(-6250 8750);
DISPLAY 1.021277 (-6250 8750);
DISPLAY INVISIBLE (-6250 8750);
FORCEADD Q_RES..1
(-6125 8800);
FORCEPROP 1 LAST PART_NUMBER CS00002JB13
J 0
(-6150 8725);
DISPLAY 0.404255 (-6150 8725);
DISPLAY INVISIBLE (-6150 8725);
FORCEPROP 1 LAST MATERIAL CHIP
J 0
(-5875 8800);
DISPLAY 0.510638 (-5875 8800);
FORCEPROP 1 LAST TOLERANCE 5%
J 0
(-5925 8800);
DISPLAY 0.510638 (-5925 8800);
FORCEPROP 1 LAST VALUE 0
J 2
(-5975 8800);
DISPLAY 0.510638 (-5975 8800);
FORCEPROP 1 LAST $LOCATION R3105
J 0
(-6300 8775);
DISPLAY 0.510638 (-6300 8775);
FORCEPROP 1 LASTPIN (-6225 8800) $PN 1
J 0
(-6213 8812);
DISPLAY 0.787234 (-6213 8812);
PAINT MONO (-6213 8812);
FORCEPROP 1 LASTPIN (-6025 8800) $PN 2
J 0
(-6063 8812);
DISPLAY 0.787234 (-6063 8812);
PAINT MONO (-6063 8812);
FORCEPROP 1 LAST PACK_TYPE 0402LF
J 0
(-6275 8750);
DISPLAY 0.404255 (-6275 8750);
DISPLAY INVISIBLE (-6275 8750);
FORCEPROP 1 LAST WATTAGE 1/16W
J 2
(-5975 8750);
DISPLAY 0.404255 (-5975 8750);
DISPLAY INVISIBLE (-5975 8750);
FORCEPROP 2 LAST CDS_LIB pure_quanta
J 0
(-6125 8800);
DISPLAY INVISIBLE (-6125 8800);
FORCEPROP 1 LAST PATH I43
J 0
(-6175 8950);
DISPLAY 0.978723 (-6175 8950);
PAINT WHITE (-6175 8950);
DISPLAY INVISIBLE (-6175 8950);
FORCEPROP 0 LAST CDS_LOCATION R3105
J 0
(-6250 8850);
DISPLAY 1.021277 (-6250 8850);
DISPLAY INVISIBLE (-6250 8850);
FORCEPROP 0 LAST $SEC 1
J 0
(-6250 8850);
DISPLAY 0.680851 (-6250 8850);
PAINT MONO (-6250 8850);
DISPLAY INVISIBLE (-6250 8850);
FORCEPROP 0 LAST CDS_SEC 1
J 0
(-6250 8850);
DISPLAY 1.021277 (-6250 8850);
DISPLAY INVISIBLE (-6250 8850);
FORCEADD Q_RES..1
(-6125 8900);
FORCEPROP 1 LAST PART_NUMBER CS00002JB13
J 0
(-6225 8975);
DISPLAY 0.404255 (-6225 8975);
DISPLAY INVISIBLE (-6225 8975);
FORCEPROP 1 LAST TOLERANCE 5%
J 0
(-5925 8900);
DISPLAY 0.510638 (-5925 8900);
FORCEPROP 1 LAST VALUE 0
J 2
(-5975 8900);
DISPLAY 0.510638 (-5975 8900);
FORCEPROP 1 LAST MATERIAL CHIP
J 0
(-5875 8900);
DISPLAY 0.510638 (-5875 8900);
FORCEPROP 1 LAST $LOCATION R2707
J 0
(-6350 8900);
DISPLAY 0.638298 (-6350 8900);
FORCEPROP 1 LASTPIN (-6225 8900) $PN 1
J 0
(-6213 8912);
DISPLAY 0.787234 (-6213 8912);
PAINT MONO (-6213 8912);
FORCEPROP 1 LASTPIN (-6025 8900) $PN 2
J 0
(-6063 8912);
DISPLAY 0.787234 (-6063 8912);
PAINT MONO (-6063 8912);
FORCEPROP 1 LAST WATTAGE 1/16W
J 2
(-5975 8850);
DISPLAY 0.404255 (-5975 8850);
DISPLAY INVISIBLE (-5975 8850);
FORCEPROP 1 LAST PACK_TYPE 0402LF
J 0
(-6275 8850);
DISPLAY 0.404255 (-6275 8850);
DISPLAY INVISIBLE (-6275 8850);
FORCEPROP 2 LAST CDS_LIB pure_quanta
J 0
(-6125 8900);
DISPLAY INVISIBLE (-6125 8900);
FORCEPROP 1 LAST PATH I44
J 0
(-6175 9050);
DISPLAY 0.978723 (-6175 9050);
PAINT WHITE (-6175 9050);
DISPLAY INVISIBLE (-6175 9050);
FORCEPROP 0 LAST CDS_LOCATION R2707
J 0
(-6000 9000);
DISPLAY 1.021277 (-6000 9000);
DISPLAY INVISIBLE (-6000 9000);
FORCEPROP 0 LAST $SEC 1
J 0
(-6000 9000);
DISPLAY 0.680851 (-6000 9000);
PAINT MONO (-6000 9000);
DISPLAY INVISIBLE (-6000 9000);
FORCEPROP 0 LAST CDS_SEC 1
J 0
(-6000 9000);
DISPLAY 1.021277 (-6000 9000);
DISPLAY INVISIBLE (-6000 9000);
FORCEADD OFFPAGE..1
(-5275 7325);
FORCEPROP 2 LAST $XR1 241 
J 0
(-5677 7325);
DISPLAY 0.638298 (-5677 7325);
PAINT MONO (-5677 7325);
FORCEPROP 2 LAST $XR0 240 
J 0
(-5557 7325);
DISPLAY 0.638298 (-5557 7325);
PAINT MONO (-5557 7325);
FORCEPROP 2 LAST CDS_LIB standard
J 0
(-5275 7325);
PAINT MONO (-5275 7325);
DISPLAY INVISIBLE (-5275 7325);
FORCEPROP 1 LAST OFFPAGE TRUE
J 0
(-4950 7200);
DISPLAY 0.872340 (-4950 7200);
DISPLAY INVISIBLE (-4950 7200);
FORCEPROP 1 LAST COMMENT_BODY TRUE
J 0
(-5150 7225);
DISPLAY 0.872340 (-5150 7225);
PAINT GREEN (-5150 7225);
DISPLAY INVISIBLE (-5150 7225);
FORCEPROP 2 LAST PATH I45
J 0
(-5550 7375);
DISPLAY 1.021277 (-5550 7375);
DISPLAY INVISIBLE (-5550 7375);
FORCEADD OFFPAGE..6
(-5275 7425);
FORCEPROP 2 LAST $XR1 241 
J 0
(-5675 7425);
DISPLAY 0.638298 (-5675 7425);
PAINT MONO (-5675 7425);
FORCEPROP 2 LAST $XR0 240 
J 0
(-5555 7425);
DISPLAY 0.638298 (-5555 7425);
PAINT MONO (-5555 7425);
FORCEPROP 2 LAST CDS_LIB standard
J 0
(-5275 7425);
PAINT MONO (-5275 7425);
DISPLAY INVISIBLE (-5275 7425);
FORCEPROP 1 LAST OFFPAGE TRUE
J 0
(-4950 7300);
DISPLAY 0.872340 (-4950 7300);
DISPLAY INVISIBLE (-4950 7300);
FORCEPROP 1 LAST COMMENT_BODY TRUE
J 0
(-5175 7350);
DISPLAY 0.872340 (-5175 7350);
PAINT GREEN (-5175 7350);
DISPLAY INVISIBLE (-5175 7350);
FORCEPROP 2 LAST PATH I46
J 0
(-5550 7475);
DISPLAY 1.021277 (-5550 7475);
DISPLAY INVISIBLE (-5550 7475);
FORCEADD OFFPAGE..4
R 2
(-5275 7525);
FORCEPROP 2 LAST $XR1 234 
J 0
(-5677 7525);
DISPLAY 0.638298 (-5677 7525);
PAINT MONO (-5677 7525);
FORCEPROP 2 LAST $XR0 213 
J 0
(-5557 7525);
DISPLAY 0.638298 (-5557 7525);
PAINT MONO (-5557 7525);
FORCEPROP 2 LAST CDS_LIB standard
J 0
(-5275 7525);
DISPLAY INVISIBLE (-5275 7525);
FORCEPROP 1 LAST OFFPAGE TRUE
J 2
(-5600 7400);
DISPLAY 0.872340 (-5600 7400);
DISPLAY INVISIBLE (-5600 7400);
FORCEPROP 1 LAST COMMENT_BODY TRUE
J 2
(-5250 7425);
DISPLAY 0.872340 (-5250 7425);
PAINT GREEN (-5250 7425);
DISPLAY INVISIBLE (-5250 7425);
FORCEPROP 2 LAST PATH I47
J 0
(-5550 7575);
DISPLAY 1.021277 (-5550 7575);
DISPLAY INVISIBLE (-5550 7575);
FORCEADD Q_RES..2
(-5050 7100);
FORCEPROP 1 LAST PART_NUMBER CS31002FB08
J 0
(-5010 6925);
DISPLAY 0.510638 (-5010 6925);
DISPLAY INVISIBLE (-5010 6925);
FORCEPROP 1 LAST WATTAGE 1/16W
J 0
(-5010 7075);
DISPLAY 0.510638 (-5010 7075);
FORCEPROP 1 LAST PACK_TYPE 0402LF
J 0
(-5010 6975);
DISPLAY 0.510638 (-5010 6975);
FORCEPROP 1 LAST VALUE 10K
J 0
(-5005 7175);
DISPLAY 0.510638 (-5005 7175);
FORCEPROP 1 LAST TOLERANCE 1%
J 0
(-5005 7125);
DISPLAY 0.510638 (-5005 7125);
FORCEPROP 1 LAST MATERIAL CHIP
J 0
(-5010 7025);
DISPLAY 0.510638 (-5010 7025);
FORCEPROP 1 LAST $LOCATION R4603
J 0
(-5005 7225);
DISPLAY 0.978723 (-5005 7225);
FORCEPROP 1 LASTPIN (-5050 7200) $PN 1
J 0
(-5045 7162);
DISPLAY 0.787234 (-5045 7162);
PAINT MONO (-5045 7162);
FORCEPROP 1 LASTPIN (-5050 7000) $PN 2
J 0
(-5045 7010);
DISPLAY 0.787234 (-5045 7010);
PAINT MONO (-5045 7010);
FORCEPROP 2 LAST CDS_LIB pure_quanta
J 0
(-5050 7100);
DISPLAY INVISIBLE (-5050 7100);
FORCEPROP 1 LAST PATH I48
J 0
(-5000 7275);
DISPLAY 0.978723 (-5000 7275);
PAINT WHITE (-5000 7275);
DISPLAY INVISIBLE (-5000 7275);
FORCEPROP 0 LAST CDS_LOCATION R4603
J 0
(-5000 7275);
DISPLAY 1.021277 (-5000 7275);
DISPLAY INVISIBLE (-5000 7275);
FORCEPROP 0 LAST $SEC 1
J 0
(-5000 7275);
DISPLAY 0.680851 (-5000 7275);
PAINT MONO (-5000 7275);
DISPLAY INVISIBLE (-5000 7275);
FORCEPROP 0 LAST CDS_SEC 1
J 0
(-5000 7275);
DISPLAY 1.021277 (-5000 7275);
DISPLAY INVISIBLE (-5000 7275);
FORCEADD UNIVERSAL_GND..1
(-5025 8475);
FORCEPROP 3 LASTPIN (-5025 8525) SIG_NAME GND\g
J 0
(-5015 8535);
DISPLAY 0.659574 (-5015 8535);
PAINT MONO (-5015 8535);
DISPLAY INVISIBLE (-5015 8535);
FORCEPROP 2 LAST CDS_LIB logical_power
J 0
(-5025 8475);
PAINT MONO (-5025 8475);
DISPLAY INVISIBLE (-5025 8475);
FORCEPROP 1 LAST HDL_POWER GND
J 1
(-5000 8400);
DISPLAY 0.872340 (-5000 8400);
PAINT GREEN (-5000 8400);
DISPLAY INVISIBLE (-5000 8400);
FORCEPROP 1 LAST PATH I49
J 0
(-4950 8475);
DISPLAY 0.872340 (-4950 8475);
PAINT AQUA (-4950 8475);
DISPLAY INVISIBLE (-4950 8475);
FORCEADD OFFPAGE..1
(-4950 4650);
FORCEPROP 2 LAST $XR1 241 
J 0
(-5352 4650);
DISPLAY 0.638298 (-5352 4650);
PAINT MONO (-5352 4650);
FORCEPROP 2 LAST $XR0 240 
J 0
(-5232 4650);
DISPLAY 0.638298 (-5232 4650);
PAINT MONO (-5232 4650);
FORCEPROP 2 LAST CDS_LIB standard
J 0
(-4950 4650);
PAINT MONO (-4950 4650);
DISPLAY INVISIBLE (-4950 4650);
FORCEPROP 1 LAST OFFPAGE TRUE
J 0
(-4625 4525);
DISPLAY 0.872340 (-4625 4525);
DISPLAY INVISIBLE (-4625 4525);
FORCEPROP 1 LAST COMMENT_BODY TRUE
J 0
(-4825 4550);
DISPLAY 0.872340 (-4825 4550);
PAINT GREEN (-4825 4550);
DISPLAY INVISIBLE (-4825 4550);
FORCEPROP 2 LAST PATH I5
J 0
(-5225 4700);
DISPLAY 1.021277 (-5225 4700);
DISPLAY INVISIBLE (-5225 4700);
FORCEADD LTC4307CMS8..1
(-4625 8750);
FORCEPROP 1 LAST PART_NUMBER AL004307000
J 0
(-4875 9010);
DISPLAY 0.723404 (-4875 9010);
PAINT GREEN (-4875 9010);
DISPLAY INVISIBLE (-4875 9010);
FORCEPROP 1 LAST MATERIAL IC
J 0
(-4875 8960);
DISPLAY 0.723404 (-4875 8960);
PAINT GREEN (-4875 8960);
FORCEPROP 2 LAST VALUE LTC4307CMS8
J 0
(-4875 9100);
DISPLAY 1.021277 (-4875 9100);
FORCEPROP 2 LAST PART_TYPE SMLF
J 0
(-4875 9150);
DISPLAY 1.021277 (-4875 9150);
FORCEPROP 1 LAST LOCATION U175
J 0
(-4875 9055);
DISPLAY 0.723404 (-4875 9055);
PAINT GREEN (-4875 9055);
FORCEPROP 0 LASTPIN (-5025 8900) $PN 1
J 2
(-5035 8910);
DISPLAY 0.680851 (-5035 8910);
PAINT MONO (-5035 8910);
FORCEPROP 0 LASTPIN (-5025 8600) $PN 4
J 2
(-5035 8610);
DISPLAY 0.680851 (-5035 8610);
PAINT MONO (-5035 8610);
FORCEPROP 0 LASTPIN (-4225 8600) $PN 5
J 0
(-4215 8610);
DISPLAY 0.680851 (-4215 8610);
PAINT MONO (-4215 8610);
FORCEPROP 0 LASTPIN (-5025 8800) $PN 3
J 2
(-5035 8810);
DISPLAY 0.680851 (-5035 8810);
PAINT MONO (-5035 8810);
FORCEPROP 0 LASTPIN (-4225 8800) $PN 2
J 0
(-4215 8810);
DISPLAY 0.680851 (-4215 8810);
PAINT MONO (-4215 8810);
FORCEPROP 0 LASTPIN (-5025 8700) $PN 6
J 2
(-5035 8710);
DISPLAY 0.680851 (-5035 8710);
PAINT MONO (-5035 8710);
FORCEPROP 0 LASTPIN (-4225 8700) $PN 7
J 0
(-4215 8710);
DISPLAY 0.680851 (-4215 8710);
PAINT MONO (-4215 8710);
FORCEPROP 0 LASTPIN (-4225 8900) $PN 8
J 0
(-4215 8910);
DISPLAY 0.680851 (-4215 8910);
PAINT MONO (-4215 8910);
FORCEPROP 1 LAST NEEDS_NO_SIZE TRUE
J 0
(-4625 8750);
DISPLAY 0.468085 (-4625 8750);
PAINT GREEN (-4625 8750);
DISPLAY INVISIBLE (-4625 8750);
FORCEPROP 2 LAST CDS_LIB pure_quanta
J 0
(-4625 8750);
DISPLAY INVISIBLE (-4625 8750);
FORCEPROP 1 LAST PATH I50
J 0
(-4400 8955);
DISPLAY 0.723404 (-4400 8955);
PAINT GREEN (-4400 8955);
DISPLAY INVISIBLE (-4400 8955);
FORCEPROP 0 LAST $SEC 1
J 0
(-4875 9200);
DISPLAY 0.680851 (-4875 9200);
PAINT MONO (-4875 9200);
DISPLAY INVISIBLE (-4875 9200);
FORCEPROP 0 LAST CDS_SEC 1
J 0
(-4875 9200);
DISPLAY 1.021277 (-4875 9200);
DISPLAY INVISIBLE (-4875 9200);
FORCEADD Q_RES..1
(-4100 7425);
FORCEPROP 1 LAST PART_NUMBER CS00002JB13
J 0
(-4125 7350);
DISPLAY 0.404255 (-4125 7350);
DISPLAY INVISIBLE (-4125 7350);
FORCEPROP 1 LAST MATERIAL CHIP
J 0
(-3850 7425);
DISPLAY 0.510638 (-3850 7425);
FORCEPROP 1 LAST VALUE 0
J 2
(-3950 7425);
DISPLAY 0.510638 (-3950 7425);
FORCEPROP 1 LAST TOLERANCE 5%
J 0
(-3900 7425);
DISPLAY 0.510638 (-3900 7425);
FORCEPROP 1 LAST $LOCATION R3109
J 0
(-4300 7425);
DISPLAY 0.510638 (-4300 7425);
FORCEPROP 1 LASTPIN (-4200 7425) $PN 1
J 0
(-4188 7437);
DISPLAY 0.787234 (-4188 7437);
PAINT MONO (-4188 7437);
FORCEPROP 1 LASTPIN (-4000 7425) $PN 2
J 0
(-4038 7437);
DISPLAY 0.787234 (-4038 7437);
PAINT MONO (-4038 7437);
FORCEPROP 1 LAST WATTAGE 1/16W
J 2
(-3950 7375);
DISPLAY 0.404255 (-3950 7375);
DISPLAY INVISIBLE (-3950 7375);
FORCEPROP 1 LAST PACK_TYPE 0402LF
J 0
(-4250 7375);
DISPLAY 0.404255 (-4250 7375);
DISPLAY INVISIBLE (-4250 7375);
FORCEPROP 2 LAST CDS_LIB pure_quanta
J 0
(-4100 7425);
DISPLAY INVISIBLE (-4100 7425);
FORCEPROP 1 LAST PATH I51
J 0
(-4150 7575);
DISPLAY 0.978723 (-4150 7575);
PAINT WHITE (-4150 7575);
DISPLAY INVISIBLE (-4150 7575);
FORCEPROP 0 LAST CDS_LOCATION R3109
J 0
(-4150 7525);
DISPLAY 1.021277 (-4150 7525);
DISPLAY INVISIBLE (-4150 7525);
FORCEPROP 0 LAST $SEC 1
J 0
(-4150 7525);
DISPLAY 0.680851 (-4150 7525);
PAINT MONO (-4150 7525);
DISPLAY INVISIBLE (-4150 7525);
FORCEPROP 0 LAST CDS_SEC 1
J 0
(-4150 7525);
DISPLAY 1.021277 (-4150 7525);
DISPLAY INVISIBLE (-4150 7525);
FORCEADD Q_RES..1
(-4100 7325);
FORCEPROP 1 LAST PART_NUMBER CS00002JB13
J 0
(-4175 7225);
DISPLAY 0.404255 (-4175 7225);
DISPLAY INVISIBLE (-4175 7225);
FORCEPROP 1 LAST VALUE 0
J 2
(-3950 7325);
DISPLAY 0.510638 (-3950 7325);
FORCEPROP 1 LAST PACK_TYPE 0402LF
J 0
(-4175 7275);
DISPLAY 0.404255 (-4175 7275);
FORCEPROP 1 LAST TOLERANCE 5%
J 0
(-3900 7325);
DISPLAY 0.510638 (-3900 7325);
FORCEPROP 1 LAST MATERIAL CHIP
J 0
(-3850 7325);
DISPLAY 0.510638 (-3850 7325);
FORCEPROP 1 LAST WATTAGE 1/16W
J 2
(-3950 7275);
DISPLAY 0.404255 (-3950 7275);
FORCEPROP 1 LAST $LOCATION R3110
J 0
(-4300 7325);
DISPLAY 0.510638 (-4300 7325);
FORCEPROP 1 LASTPIN (-4200 7325) $PN 1
J 0
(-4188 7337);
DISPLAY 0.787234 (-4188 7337);
PAINT MONO (-4188 7337);
FORCEPROP 1 LASTPIN (-4000 7325) $PN 2
J 0
(-4038 7337);
DISPLAY 0.787234 (-4038 7337);
PAINT MONO (-4038 7337);
FORCEPROP 2 LAST CDS_LIB pure_quanta
J 0
(-4100 7325);
DISPLAY INVISIBLE (-4100 7325);
FORCEPROP 1 LAST PATH I52
J 0
(-4150 7475);
DISPLAY 0.978723 (-4150 7475);
PAINT WHITE (-4150 7475);
DISPLAY INVISIBLE (-4150 7475);
FORCEPROP 0 LAST CDS_LOCATION R3110
J 0
(-4150 7425);
DISPLAY 1.021277 (-4150 7425);
DISPLAY INVISIBLE (-4150 7425);
FORCEPROP 0 LAST $SEC 1
J 0
(-4150 7425);
DISPLAY 0.680851 (-4150 7425);
PAINT MONO (-4150 7425);
DISPLAY INVISIBLE (-4150 7425);
FORCEPROP 0 LAST CDS_SEC 1
J 0
(-4150 7425);
DISPLAY 1.021277 (-4150 7425);
DISPLAY INVISIBLE (-4150 7425);
FORCEADD Q_RES..1
(-4100 7525);
FORCEPROP 1 LAST PART_NUMBER CS00002JB13
J 0
(-4200 7475);
DISPLAY 0.404255 (-4200 7475);
DISPLAY INVISIBLE (-4200 7475);
FORCEPROP 1 LAST TOLERANCE 5%
J 0
(-3900 7525);
DISPLAY 0.510638 (-3900 7525);
FORCEPROP 1 LAST MATERIAL CHIP
J 0
(-3850 7525);
DISPLAY 0.510638 (-3850 7525);
FORCEPROP 1 LAST VALUE 0
J 2
(-3950 7525);
DISPLAY 0.510638 (-3950 7525);
FORCEPROP 1 LAST $LOCATION R2899
J 0
(-4325 7525);
DISPLAY 0.638298 (-4325 7525);
FORCEPROP 1 LASTPIN (-4200 7525) $PN 1
J 0
(-4188 7537);
DISPLAY 0.787234 (-4188 7537);
PAINT MONO (-4188 7537);
FORCEPROP 1 LASTPIN (-4000 7525) $PN 2
J 0
(-4038 7537);
DISPLAY 0.787234 (-4038 7537);
PAINT MONO (-4038 7537);
FORCEPROP 2 LAST CDS_LIB pure_quanta
J 0
(-4100 7525);
DISPLAY INVISIBLE (-4100 7525);
FORCEPROP 1 LAST PACK_TYPE 0402LF
J 0
(-4200 7425);
DISPLAY 0.404255 (-4200 7425);
DISPLAY INVISIBLE (-4200 7425);
FORCEPROP 1 LAST WATTAGE 1/16W
J 2
(-3975 7425);
DISPLAY 0.404255 (-3975 7425);
DISPLAY INVISIBLE (-3975 7425);
FORCEPROP 1 LAST PATH I53
J 0
(-4150 7675);
DISPLAY 0.978723 (-4150 7675);
PAINT WHITE (-4150 7675);
DISPLAY INVISIBLE (-4150 7675);
FORCEPROP 0 LAST CDS_LOCATION R2899
J 0
(-3975 7625);
DISPLAY 1.021277 (-3975 7625);
DISPLAY INVISIBLE (-3975 7625);
FORCEPROP 0 LAST $SEC 1
J 0
(-3975 7625);
DISPLAY 0.680851 (-3975 7625);
PAINT MONO (-3975 7625);
DISPLAY INVISIBLE (-3975 7625);
FORCEPROP 0 LAST CDS_SEC 1
J 0
(-3975 7625);
DISPLAY 1.021277 (-3975 7625);
DISPLAY INVISIBLE (-3975 7625);
FORCEADD Q_RES..1
(-4650 8275);
FORCEPROP 1 LAST PART_NUMBER CS00002JB13
J 0
(-4750 8225);
DISPLAY 0.404255 (-4750 8225);
DISPLAY INVISIBLE (-4750 8225);
FORCEPROP 1 LAST MATERIAL EMPTY
J 0
(-4350 8275);
DISPLAY 0.510638 (-4350 8275);
PAINT RED (-4350 8275);
FORCEPROP 1 LAST VALUE 0
J 2
(-4500 8275);
DISPLAY 0.510638 (-4500 8275);
FORCEPROP 1 LAST WATTAGE 1/16W
J 2
(-4525 8175);
DISPLAY 0.404255 (-4525 8175);
FORCEPROP 1 LAST PACK_TYPE 0402LF
J 0
(-4750 8175);
DISPLAY 0.404255 (-4750 8175);
FORCEPROP 1 LAST TOLERANCE 5%
J 0
(-4425 8275);
DISPLAY 0.510638 (-4425 8275);
FORCEPROP 1 LAST $LOCATION R2724
J 0
(-4825 8275);
DISPLAY 0.638298 (-4825 8275);
FORCEPROP 1 LASTPIN (-4750 8275) $PN 1
J 0
(-4738 8287);
DISPLAY 0.787234 (-4738 8287);
PAINT MONO (-4738 8287);
FORCEPROP 1 LASTPIN (-4550 8275) $PN 2
J 0
(-4588 8287);
DISPLAY 0.787234 (-4588 8287);
PAINT MONO (-4588 8287);
FORCEPROP 2 LAST CDS_LIB pure_quanta
J 0
(-4650 8275);
DISPLAY INVISIBLE (-4650 8275);
FORCEPROP 1 LAST PATH I54
J 0
(-4700 8425);
DISPLAY 0.978723 (-4700 8425);
PAINT WHITE (-4700 8425);
DISPLAY INVISIBLE (-4700 8425);
FORCEPROP 2 LAST CDS_LOCATION R2724
J 0
(-4700 8475);
DISPLAY 1.021277 (-4700 8475);
DISPLAY INVISIBLE (-4700 8475);
FORCEPROP 2 LAST $SEC 1
J 0
(-4700 8475);
DISPLAY 0.680851 (-4700 8475);
PAINT MONO (-4700 8475);
DISPLAY INVISIBLE (-4700 8475);
FORCEPROP 2 LAST CDS_SEC 1
J 0
(-4700 8475);
DISPLAY 1.021277 (-4700 8475);
DISPLAY INVISIBLE (-4700 8475);
FORCEADD Q_RES..1
(-4650 8350);
FORCEPROP 1 LAST PART_NUMBER CS00002JB13
J 0
(-4750 8300);
DISPLAY 0.404255 (-4750 8300);
DISPLAY INVISIBLE (-4750 8300);
FORCEPROP 1 LAST VALUE 0
J 2
(-4500 8350);
DISPLAY 0.510638 (-4500 8350);
FORCEPROP 1 LAST MATERIAL EMPTY
J 0
(-4350 8350);
DISPLAY 0.510638 (-4350 8350);
PAINT RED (-4350 8350);
FORCEPROP 1 LAST $LOCATION R2705
J 0
(-4825 8350);
DISPLAY 0.638298 (-4825 8350);
FORCEPROP 1 LASTPIN (-4750 8350) $PN 1
J 0
(-4738 8362);
DISPLAY 0.787234 (-4738 8362);
PAINT MONO (-4738 8362);
FORCEPROP 1 LASTPIN (-4550 8350) $PN 2
J 0
(-4588 8362);
DISPLAY 0.787234 (-4588 8362);
PAINT MONO (-4588 8362);
FORCEPROP 1 LAST WATTAGE 1/16W
J 2
(-4525 8250);
DISPLAY 0.404255 (-4525 8250);
DISPLAY INVISIBLE (-4525 8250);
FORCEPROP 1 LAST TOLERANCE 5%
J 0
(-4425 8350);
DISPLAY 0.510638 (-4425 8350);
DISPLAY INVISIBLE (-4425 8350);
FORCEPROP 1 LAST PACK_TYPE 0402LF
J 0
(-4750 8250);
DISPLAY 0.404255 (-4750 8250);
DISPLAY INVISIBLE (-4750 8250);
FORCEPROP 2 LAST CDS_LIB pure_quanta
J 0
(-4650 8350);
DISPLAY INVISIBLE (-4650 8350);
FORCEPROP 1 LAST PATH I55
J 0
(-4700 8500);
DISPLAY 0.978723 (-4700 8500);
PAINT WHITE (-4700 8500);
DISPLAY INVISIBLE (-4700 8500);
FORCEPROP 0 LAST CDS_LOCATION R2705
J 0
(-4525 8450);
DISPLAY 1.021277 (-4525 8450);
DISPLAY INVISIBLE (-4525 8450);
FORCEPROP 0 LAST $SEC 1
J 0
(-4525 8450);
DISPLAY 0.680851 (-4525 8450);
PAINT MONO (-4525 8450);
DISPLAY INVISIBLE (-4525 8450);
FORCEPROP 0 LAST CDS_SEC 1
J 0
(-4525 8450);
DISPLAY 1.021277 (-4525 8450);
DISPLAY INVISIBLE (-4525 8450);
FORCEADD UNIVERSAL_GND..1
(-4000 8925);
FORCEPROP 3 LASTPIN (-4000 8975) SIG_NAME GND\g
J 0
(-3990 8985);
DISPLAY 0.659574 (-3990 8985);
PAINT MONO (-3990 8985);
DISPLAY INVISIBLE (-3990 8985);
FORCEPROP 2 LAST CDS_LIB logical_power
J 0
(-4000 8925);
PAINT MONO (-4000 8925);
DISPLAY INVISIBLE (-4000 8925);
FORCEPROP 1 LAST HDL_POWER GND
J 1
(-3975 8850);
DISPLAY 0.872340 (-3975 8850);
PAINT GREEN (-3975 8850);
DISPLAY INVISIBLE (-3975 8850);
FORCEPROP 1 LAST PATH I56
J 0
(-3925 8925);
DISPLAY 0.872340 (-3925 8925);
PAINT AQUA (-3925 8925);
DISPLAY INVISIBLE (-3925 8925);
FORCEADD UNIVERSAL_POWER..1
(-4175 9450);
FORCEPROP 3 LASTPIN (-4175 9400) SIG_NAME P3V3_AUX\g
J 0
(-4165 9410);
DISPLAY 0.659574 (-4165 9410);
PAINT MONO (-4165 9410);
DISPLAY INVISIBLE (-4165 9410);
FORCEPROP 1 LAST HDL_POWER P3V3_AUX
J 1
(-4175 9500);
DISPLAY 0.872340 (-4175 9500);
PAINT GREEN (-4175 9500);
FORCEPROP 2 LAST CDS_LIB logical_power
J 0
(-4175 9450);
PAINT MONO (-4175 9450);
DISPLAY INVISIBLE (-4175 9450);
FORCEPROP 1 LAST PATH I57
J 0
(-4125 9475);
DISPLAY 0.872340 (-4125 9475);
PAINT AQUA (-4125 9475);
DISPLAY INVISIBLE (-4125 9475);
FORCEADD Q_CAP..1
(-4000 9150);
FORCEPROP 1 LAST PART_NUMBER CH4104K1B00
J 0
(-3950 9000);
DISPLAY 0.510638 (-3950 9000);
DISPLAY INVISIBLE (-3950 9000);
FORCEPROP 1 LAST VALUE 0.1UF
J 0
(-3950 9200);
DISPLAY 0.510638 (-3950 9200);
FORCEPROP 1 LAST VOLTAGE 25V
J 0
(-3950 9150);
DISPLAY 0.510638 (-3950 9150);
FORCEPROP 1 LAST TOLERANCE 10%
J 0
(-3950 9100);
DISPLAY 0.510638 (-3950 9100);
FORCEPROP 1 LAST MATERIAL X7R
J 0
(-3950 9050);
DISPLAY 0.510638 (-3950 9050);
FORCEPROP 1 LAST PACK_TYPE 0402
J 0
(-3950 8950);
DISPLAY 0.510638 (-3950 8950);
FORCEPROP 1 LAST $LOCATION C1707
J 0
(-3950 9250);
DISPLAY 0.978723 (-3950 9250);
FORCEPROP 1 LASTPIN (-4000 9250) $PN 1
J 0
(-3990 9230);
DISPLAY 0.787234 (-3990 9230);
FORCEPROP 1 LASTPIN (-4000 9050) $PN 2
J 0
(-3990 9030);
DISPLAY 0.787234 (-3990 9030);
FORCEPROP 2 LAST CDS_LIB pure_quanta
J 0
(-4000 9150);
PAINT MONO (-4000 9150);
DISPLAY INVISIBLE (-4000 9150);
FORCEPROP 1 LAST PATH I58
J 0
(-3950 9300);
DISPLAY 0.978723 (-3950 9300);
PAINT WHITE (-3950 9300);
DISPLAY INVISIBLE (-3950 9300);
FORCEPROP 2 LAST CDS_LOCATION C1707
J 0
(-3950 9350);
DISPLAY 1.021277 (-3950 9350);
DISPLAY INVISIBLE (-3950 9350);
FORCEPROP 2 LAST $SEC 1
J 0
(-3950 9350);
DISPLAY 0.680851 (-3950 9350);
PAINT MONO (-3950 9350);
DISPLAY INVISIBLE (-3950 9350);
FORCEPROP 2 LAST CDS_SEC 1
J 0
(-3950 9350);
DISPLAY 1.021277 (-3950 9350);
DISPLAY INVISIBLE (-3950 9350);
FORCEADD Q_RES..2
(-3150 9125);
FORCEPROP 1 LAST PART_NUMBER CS31002FB08
J 0
(-3110 9000);
DISPLAY 0.404255 (-3110 9000);
DISPLAY INVISIBLE (-3110 9000);
FORCEPROP 1 LAST WATTAGE 1/16W
J 0
(-3110 9100);
DISPLAY 0.404255 (-3110 9100);
FORCEPROP 1 LAST MATERIAL CHIP
J 0
(-3110 9050);
DISPLAY 0.404255 (-3110 9050);
FORCEPROP 1 LAST PACK_TYPE 0402LF
J 0
(-3110 8950);
DISPLAY 0.404255 (-3110 8950);
FORCEPROP 1 LAST TOLERANCE 1%
J 0
(-3105 9150);
DISPLAY 0.404255 (-3105 9150);
FORCEPROP 1 LAST VALUE 10K
J 0
(-3105 9200);
DISPLAY 0.404255 (-3105 9200);
FORCEPROP 1 LAST $LOCATION R2667
J 0
(-3105 9250);
DISPLAY 0.404255 (-3105 9250);
FORCEPROP 1 LASTPIN (-3150 9225) $PN 1
J 0
(-3145 9187);
DISPLAY 0.787234 (-3145 9187);
PAINT MONO (-3145 9187);
FORCEPROP 1 LASTPIN (-3150 9025) $PN 2
J 0
(-3145 9035);
DISPLAY 0.787234 (-3145 9035);
PAINT MONO (-3145 9035);
FORCEPROP 2 LAST CDS_LIB pure_quanta
J 0
(-3150 9125);
DISPLAY INVISIBLE (-3150 9125);
FORCEPROP 1 LAST PATH I59
J 0
(-3100 9300);
DISPLAY 0.978723 (-3100 9300);
PAINT WHITE (-3100 9300);
DISPLAY INVISIBLE (-3100 9300);
FORCEPROP 2 LAST CDS_LOCATION R2667
J 0
(-3100 9350);
DISPLAY 1.021277 (-3100 9350);
DISPLAY INVISIBLE (-3100 9350);
FORCEPROP 0 LAST $SEC 1
J 0
(-3100 9275);
DISPLAY 0.680851 (-3100 9275);
PAINT MONO (-3100 9275);
DISPLAY INVISIBLE (-3100 9275);
FORCEPROP 2 LAST CDS_SEC 1
J 0
(-3100 9350);
DISPLAY 1.021277 (-3100 9350);
DISPLAY INVISIBLE (-3100 9350);
FORCEADD OFFPAGE..4
R 2
(-4950 4750);
FORCEPROP 2 LAST $XR1 234 
J 0
(-5352 4750);
DISPLAY 0.638298 (-5352 4750);
PAINT MONO (-5352 4750);
FORCEPROP 2 LAST $XR0 213 
J 0
(-5232 4750);
DISPLAY 0.638298 (-5232 4750);
PAINT MONO (-5232 4750);
FORCEPROP 2 LAST CDS_LIB standard
J 2
(-4950 4750);
DISPLAY INVISIBLE (-4950 4750);
FORCEPROP 1 LAST OFFPAGE TRUE
J 2
(-5275 4625);
DISPLAY 0.872340 (-5275 4625);
DISPLAY INVISIBLE (-5275 4625);
FORCEPROP 1 LAST COMMENT_BODY TRUE
J 2
(-4925 4650);
DISPLAY 0.872340 (-4925 4650);
PAINT GREEN (-4925 4650);
DISPLAY INVISIBLE (-4925 4650);
FORCEPROP 2 LAST PATH I6
J 0
(-5225 4800);
DISPLAY 1.021277 (-5225 4800);
DISPLAY INVISIBLE (-5225 4800);
FORCEADD UNIVERSAL_POWER..1
(-3150 9450);
FORCEPROP 3 LASTPIN (-3150 9400) SIG_NAME P3V3_AUX\g
J 0
(-3140 9410);
DISPLAY 0.659574 (-3140 9410);
PAINT MONO (-3140 9410);
DISPLAY INVISIBLE (-3140 9410);
FORCEPROP 1 LAST HDL_POWER P3V3_AUX
J 1
(-3150 9500);
DISPLAY 0.872340 (-3150 9500);
PAINT GREEN (-3150 9500);
FORCEPROP 2 LAST CDS_LIB logical_power
J 0
(-3150 9450);
PAINT MONO (-3150 9450);
DISPLAY INVISIBLE (-3150 9450);
FORCEPROP 1 LAST PATH I60
J 0
(-3100 9475);
DISPLAY 0.872340 (-3100 9475);
PAINT AQUA (-3100 9475);
DISPLAY INVISIBLE (-3100 9475);
FORCEADD Q_RES..2
(-2900 9125);
FORCEPROP 1 LAST PART_NUMBER CS31002FB08
J 0
(-2860 9000);
DISPLAY 0.404255 (-2860 9000);
DISPLAY INVISIBLE (-2860 9000);
FORCEPROP 1 LAST MATERIAL CHIP
J 0
(-2860 9050);
DISPLAY 0.404255 (-2860 9050);
FORCEPROP 1 LAST WATTAGE 1/16W
J 0
(-2860 9100);
DISPLAY 0.404255 (-2860 9100);
FORCEPROP 1 LAST PACK_TYPE 0402LF
J 0
(-2860 8950);
DISPLAY 0.404255 (-2860 8950);
FORCEPROP 1 LAST TOLERANCE 1%
J 0
(-2855 9150);
DISPLAY 0.404255 (-2855 9150);
FORCEPROP 1 LAST VALUE 10K
J 0
(-2855 9200);
DISPLAY 0.404255 (-2855 9200);
FORCEPROP 1 LAST $LOCATION R2669
J 0
(-2855 9250);
DISPLAY 0.404255 (-2855 9250);
FORCEPROP 1 LASTPIN (-2900 9225) $PN 1
J 0
(-2895 9187);
DISPLAY 0.787234 (-2895 9187);
PAINT MONO (-2895 9187);
FORCEPROP 1 LASTPIN (-2900 9025) $PN 2
J 0
(-2895 9035);
DISPLAY 0.787234 (-2895 9035);
PAINT MONO (-2895 9035);
FORCEPROP 2 LAST CDS_LIB pure_quanta
J 0
(-2900 9125);
DISPLAY INVISIBLE (-2900 9125);
FORCEPROP 1 LAST PATH I61
J 0
(-2850 9300);
DISPLAY 0.978723 (-2850 9300);
PAINT WHITE (-2850 9300);
DISPLAY INVISIBLE (-2850 9300);
FORCEPROP 2 LAST CDS_LOCATION R2669
J 0
(-2850 9350);
DISPLAY 1.021277 (-2850 9350);
DISPLAY INVISIBLE (-2850 9350);
FORCEPROP 0 LAST $SEC 1
J 0
(-2850 9275);
DISPLAY 0.680851 (-2850 9275);
PAINT MONO (-2850 9275);
DISPLAY INVISIBLE (-2850 9275);
FORCEPROP 2 LAST CDS_SEC 1
J 0
(-2850 9350);
DISPLAY 1.021277 (-2850 9350);
DISPLAY INVISIBLE (-2850 9350);
FORCEADD UNIVERSAL_GND..1
(-2725 7100);
FORCEPROP 3 LASTPIN (-2725 7150) SIG_NAME GND\g
J 0
(-2715 7160);
DISPLAY 0.659574 (-2715 7160);
PAINT MONO (-2715 7160);
DISPLAY INVISIBLE (-2715 7160);
FORCEPROP 2 LAST CDS_LIB logical_power
J 0
(-2725 7100);
PAINT MONO (-2725 7100);
DISPLAY INVISIBLE (-2725 7100);
FORCEPROP 1 LAST HDL_POWER GND
J 1
(-2700 7025);
DISPLAY 0.872340 (-2700 7025);
PAINT GREEN (-2700 7025);
DISPLAY INVISIBLE (-2700 7025);
FORCEPROP 1 LAST PATH I62
J 0
(-2650 7100);
DISPLAY 0.872340 (-2650 7100);
PAINT AQUA (-2650 7100);
DISPLAY INVISIBLE (-2650 7100);
FORCEADD LTC4307CMS8..1
(-2250 7375);
FORCEPROP 1 LAST PART_NUMBER AL004307000
J 0
(-2500 7635);
DISPLAY 0.723404 (-2500 7635);
PAINT GREEN (-2500 7635);
DISPLAY INVISIBLE (-2500 7635);
FORCEPROP 2 LAST VALUE LTC4307CMS8
J 0
(-2500 7725);
DISPLAY 1.021277 (-2500 7725);
FORCEPROP 1 LAST MATERIAL IC
J 0
(-2500 7585);
DISPLAY 0.723404 (-2500 7585);
PAINT GREEN (-2500 7585);
FORCEPROP 2 LAST PART_TYPE SMLF
J 0
(-2500 7775);
DISPLAY 1.021277 (-2500 7775);
FORCEPROP 1 LAST LOCATION U194
J 0
(-2500 7680);
DISPLAY 0.723404 (-2500 7680);
PAINT GREEN (-2500 7680);
FORCEPROP 0 LASTPIN (-2650 7525) $PN 1
J 2
(-2660 7535);
DISPLAY 0.680851 (-2660 7535);
PAINT MONO (-2660 7535);
FORCEPROP 0 LASTPIN (-2650 7225) $PN 4
J 2
(-2660 7235);
DISPLAY 0.680851 (-2660 7235);
PAINT MONO (-2660 7235);
FORCEPROP 0 LASTPIN (-1850 7225) $PN 5
J 0
(-1840 7235);
DISPLAY 0.680851 (-1840 7235);
PAINT MONO (-1840 7235);
FORCEPROP 0 LASTPIN (-2650 7425) $PN 3
J 2
(-2660 7435);
DISPLAY 0.680851 (-2660 7435);
PAINT MONO (-2660 7435);
FORCEPROP 0 LASTPIN (-1850 7425) $PN 2
J 0
(-1840 7435);
DISPLAY 0.680851 (-1840 7435);
PAINT MONO (-1840 7435);
FORCEPROP 0 LASTPIN (-2650 7325) $PN 6
J 2
(-2660 7335);
DISPLAY 0.680851 (-2660 7335);
PAINT MONO (-2660 7335);
FORCEPROP 0 LASTPIN (-1850 7325) $PN 7
J 0
(-1840 7335);
DISPLAY 0.680851 (-1840 7335);
PAINT MONO (-1840 7335);
FORCEPROP 0 LASTPIN (-1850 7525) $PN 8
J 0
(-1840 7535);
DISPLAY 0.680851 (-1840 7535);
PAINT MONO (-1840 7535);
FORCEPROP 2 LAST CDS_LIB pure_quanta
J 0
(-2250 7375);
DISPLAY INVISIBLE (-2250 7375);
FORCEPROP 1 LAST NEEDS_NO_SIZE TRUE
J 0
(-2250 7375);
DISPLAY 0.468085 (-2250 7375);
PAINT GREEN (-2250 7375);
DISPLAY INVISIBLE (-2250 7375);
FORCEPROP 1 LAST PATH I63
J 0
(-2025 7580);
DISPLAY 0.723404 (-2025 7580);
PAINT GREEN (-2025 7580);
DISPLAY INVISIBLE (-2025 7580);
FORCEPROP 0 LAST $SEC 1
J 0
(-2500 7825);
DISPLAY 0.680851 (-2500 7825);
PAINT MONO (-2500 7825);
DISPLAY INVISIBLE (-2500 7825);
FORCEPROP 0 LAST CDS_SEC 1
J 0
(-2500 7825);
DISPLAY 1.021277 (-2500 7825);
DISPLAY INVISIBLE (-2500 7825);
FORCEADD Q_RES..1
(-2600 8700);
FORCEPROP 1 LAST PART_NUMBER CS03322FB03
J 0
(-2725 8750);
DISPLAY 0.404255 (-2725 8750);
DISPLAY INVISIBLE (-2725 8750);
FORCEPROP 1 LAST TOLERANCE 1%
J 0
(-2375 8700);
DISPLAY 0.510638 (-2375 8700);
FORCEPROP 1 LAST VALUE 33.2
J 2
(-2400 8700);
DISPLAY 0.510638 (-2400 8700);
FORCEPROP 1 LAST MATERIAL CHIP
J 0
(-2300 8700);
DISPLAY 0.510638 (-2300 8700);
FORCEPROP 1 LAST $LOCATION R2672
J 0
(-2825 8700);
DISPLAY 0.638298 (-2825 8700);
FORCEPROP 1 LASTPIN (-2700 8700) $PN 1
J 0
(-2688 8712);
DISPLAY 0.787234 (-2688 8712);
PAINT MONO (-2688 8712);
FORCEPROP 1 LASTPIN (-2500 8700) $PN 2
J 0
(-2538 8712);
DISPLAY 0.787234 (-2538 8712);
PAINT MONO (-2538 8712);
FORCEPROP 2 LAST CDS_LIB pure_quanta
J 0
(-2600 8700);
DISPLAY INVISIBLE (-2600 8700);
FORCEPROP 1 LAST PACK_TYPE 0402LF
J 0
(-2725 8800);
DISPLAY 0.404255 (-2725 8800);
DISPLAY INVISIBLE (-2725 8800);
FORCEPROP 1 LAST WATTAGE 1/16W
J 2
(-2500 8800);
DISPLAY 0.404255 (-2500 8800);
DISPLAY INVISIBLE (-2500 8800);
FORCEPROP 1 LAST PATH I64
J 0
(-2650 8850);
DISPLAY 0.978723 (-2650 8850);
PAINT WHITE (-2650 8850);
DISPLAY INVISIBLE (-2650 8850);
FORCEPROP 0 LAST CDS_LOCATION R2672
J 0
(-2825 8750);
DISPLAY 1.021277 (-2825 8750);
DISPLAY INVISIBLE (-2825 8750);
FORCEPROP 0 LAST $SEC 1
J 0
(-2825 8750);
DISPLAY 0.680851 (-2825 8750);
PAINT MONO (-2825 8750);
DISPLAY INVISIBLE (-2825 8750);
FORCEPROP 0 LAST CDS_SEC 1
J 0
(-2825 8750);
DISPLAY 1.021277 (-2825 8750);
DISPLAY INVISIBLE (-2825 8750);
FORCEADD Q_RES..1
(-2600 8800);
FORCEPROP 1 LAST PART_NUMBER CS03322FB03
J 0
(-2725 8850);
DISPLAY 0.404255 (-2725 8850);
DISPLAY INVISIBLE (-2725 8850);
FORCEPROP 1 LAST TOLERANCE 1%
J 0
(-2375 8800);
DISPLAY 0.510638 (-2375 8800);
FORCEPROP 1 LAST MATERIAL CHIP
J 0
(-2300 8800);
DISPLAY 0.510638 (-2300 8800);
FORCEPROP 1 LAST PACK_TYPE 0402LF
J 0
(-2725 8900);
DISPLAY 0.404255 (-2725 8900);
FORCEPROP 1 LAST VALUE 33.2
J 2
(-2400 8800);
DISPLAY 0.510638 (-2400 8800);
FORCEPROP 1 LAST WATTAGE 1/16W
J 2
(-2500 8900);
DISPLAY 0.404255 (-2500 8900);
FORCEPROP 1 LAST $LOCATION R2671
J 0
(-2825 8800);
DISPLAY 0.638298 (-2825 8800);
FORCEPROP 1 LASTPIN (-2700 8800) $PN 1
J 0
(-2688 8812);
DISPLAY 0.787234 (-2688 8812);
PAINT MONO (-2688 8812);
FORCEPROP 1 LASTPIN (-2500 8800) $PN 2
J 0
(-2538 8812);
DISPLAY 0.787234 (-2538 8812);
PAINT MONO (-2538 8812);
FORCEPROP 2 LAST CDS_LIB pure_quanta
J 0
(-2600 8800);
DISPLAY INVISIBLE (-2600 8800);
FORCEPROP 1 LAST PATH I65
J 0
(-2650 8950);
DISPLAY 0.978723 (-2650 8950);
PAINT WHITE (-2650 8950);
DISPLAY INVISIBLE (-2650 8950);
FORCEPROP 0 LAST CDS_LOCATION R2671
J 0
(-2500 8925);
DISPLAY 1.021277 (-2500 8925);
DISPLAY INVISIBLE (-2500 8925);
FORCEPROP 0 LAST $SEC 1
J 0
(-2500 8925);
DISPLAY 0.680851 (-2500 8925);
PAINT MONO (-2500 8925);
DISPLAY INVISIBLE (-2500 8925);
FORCEPROP 0 LAST CDS_SEC 1
J 0
(-2500 8925);
DISPLAY 1.021277 (-2500 8925);
DISPLAY INVISIBLE (-2500 8925);
FORCEADD Q_CAP..1
(-1525 7775);
FORCEPROP 1 LAST PART_NUMBER CH4104K1B00
J 0
(-1475 7625);
DISPLAY 0.510638 (-1475 7625);
DISPLAY INVISIBLE (-1475 7625);
FORCEPROP 1 LAST VALUE 0.1UF
J 0
(-1475 7825);
DISPLAY 0.510638 (-1475 7825);
FORCEPROP 1 LAST MATERIAL X7R
J 0
(-1475 7675);
DISPLAY 0.510638 (-1475 7675);
FORCEPROP 1 LAST VOLTAGE 25V
J 0
(-1475 7775);
DISPLAY 0.510638 (-1475 7775);
FORCEPROP 1 LAST TOLERANCE 10%
J 0
(-1475 7725);
DISPLAY 0.510638 (-1475 7725);
FORCEPROP 1 LAST PACK_TYPE 0402
J 0
(-1475 7575);
DISPLAY 0.510638 (-1475 7575);
FORCEPROP 1 LAST $LOCATION C1766
J 0
(-1475 7875);
DISPLAY 0.978723 (-1475 7875);
FORCEPROP 1 LASTPIN (-1525 7875) $PN 1
J 0
(-1515 7855);
DISPLAY 0.787234 (-1515 7855);
FORCEPROP 1 LASTPIN (-1525 7675) $PN 2
J 0
(-1515 7655);
DISPLAY 0.787234 (-1515 7655);
FORCEPROP 2 LAST CDS_LIB pure_quanta
J 0
(-1525 7775);
PAINT MONO (-1525 7775);
DISPLAY INVISIBLE (-1525 7775);
FORCEPROP 1 LAST PATH I66
J 0
(-1475 7925);
DISPLAY 0.978723 (-1475 7925);
PAINT WHITE (-1475 7925);
DISPLAY INVISIBLE (-1475 7925);
FORCEPROP 2 LAST CDS_LOCATION C1766
J 0
(-1475 7975);
DISPLAY 1.021277 (-1475 7975);
DISPLAY INVISIBLE (-1475 7975);
FORCEPROP 2 LAST $SEC 1
J 0
(-1475 7975);
DISPLAY 0.680851 (-1475 7975);
PAINT MONO (-1475 7975);
DISPLAY INVISIBLE (-1475 7975);
FORCEPROP 2 LAST CDS_SEC 1
J 0
(-1475 7975);
DISPLAY 1.021277 (-1475 7975);
DISPLAY INVISIBLE (-1475 7975);
FORCEADD UNIVERSAL_GND..1
(-1525 7550);
FORCEPROP 3 LASTPIN (-1525 7600) SIG_NAME GND\g
J 0
(-1515 7610);
DISPLAY 0.659574 (-1515 7610);
PAINT MONO (-1515 7610);
DISPLAY INVISIBLE (-1515 7610);
FORCEPROP 2 LAST CDS_LIB logical_power
J 0
(-1525 7550);
PAINT MONO (-1525 7550);
DISPLAY INVISIBLE (-1525 7550);
FORCEPROP 1 LAST HDL_POWER GND
J 1
(-1500 7475);
DISPLAY 0.872340 (-1500 7475);
PAINT GREEN (-1500 7475);
DISPLAY INVISIBLE (-1500 7475);
FORCEPROP 1 LAST PATH I67
J 0
(-1450 7550);
DISPLAY 0.872340 (-1450 7550);
PAINT AQUA (-1450 7550);
DISPLAY INVISIBLE (-1450 7550);
FORCEADD UNIVERSAL_POWER..1
(-1700 8075);
FORCEPROP 3 LASTPIN (-1700 8025) SIG_NAME P3V3_AUX\g
J 0
(-1690 8035);
DISPLAY 0.659574 (-1690 8035);
PAINT MONO (-1690 8035);
DISPLAY INVISIBLE (-1690 8035);
FORCEPROP 1 LAST HDL_POWER P3V3_AUX
J 1
(-1700 8125);
DISPLAY 0.872340 (-1700 8125);
PAINT GREEN (-1700 8125);
FORCEPROP 2 LAST CDS_LIB logical_power
J 0
(-1700 8075);
PAINT MONO (-1700 8075);
DISPLAY INVISIBLE (-1700 8075);
FORCEPROP 1 LAST PATH I68
J 0
(-1650 8100);
DISPLAY 0.872340 (-1650 8100);
PAINT AQUA (-1650 8100);
DISPLAY INVISIBLE (-1650 8100);
FORCEADD OFFPAGE..3
(-1275 8800);
FORCEPROP 2 LAST $XR0 140 
J 0
(-1061 8800);
DISPLAY 0.638298 (-1061 8800);
PAINT MONO (-1061 8800);
FORCEPROP 2 LAST CDS_LIB standard
J 0
(-1275 8800);
PAINT MONO (-1275 8800);
DISPLAY INVISIBLE (-1275 8800);
FORCEPROP 1 LAST OFFPAGE TRUE
J 0
(-950 8675);
DISPLAY 0.872340 (-950 8675);
PAINT GREEN (-950 8675);
DISPLAY INVISIBLE (-950 8675);
FORCEPROP 1 LAST COMMENT_BODY TRUE
J 0
(-1325 8700);
DISPLAY 0.872340 (-1325 8700);
PAINT GREEN (-1325 8700);
DISPLAY INVISIBLE (-1325 8700);
FORCEPROP 2 LAST PATH I69
J 0
(-1050 8850);
DISPLAY 1.021277 (-1050 8850);
DISPLAY INVISIBLE (-1050 8850);
FORCEADD Q_RES..1
(-6175 5975);
FORCEPROP 1 LAST PART_NUMBER CS00002JB13
J 0
(-6250 5875);
DISPLAY 0.404255 (-6250 5875);
DISPLAY INVISIBLE (-6250 5875);
FORCEPROP 1 LAST PACK_TYPE 0402LF
J 0
(-6250 5925);
DISPLAY 0.404255 (-6250 5925);
FORCEPROP 1 LAST MATERIAL CHIP
J 0
(-5925 5975);
DISPLAY 0.510638 (-5925 5975);
FORCEPROP 1 LAST TOLERANCE 5%
J 0
(-5975 5975);
DISPLAY 0.510638 (-5975 5975);
FORCEPROP 1 LAST VALUE 0
J 2
(-6025 5975);
DISPLAY 0.510638 (-6025 5975);
FORCEPROP 1 LAST WATTAGE 1/16W
J 2
(-6025 5925);
DISPLAY 0.404255 (-6025 5925);
FORCEPROP 1 LAST $LOCATION R3108
J 0
(-6325 5950);
DISPLAY 0.510638 (-6325 5950);
FORCEPROP 1 LASTPIN (-6275 5975) $PN 1
J 0
(-6263 5987);
DISPLAY 0.787234 (-6263 5987);
PAINT MONO (-6263 5987);
FORCEPROP 1 LASTPIN (-6075 5975) $PN 2
J 0
(-6113 5987);
DISPLAY 0.787234 (-6113 5987);
PAINT MONO (-6113 5987);
FORCEPROP 2 LAST CDS_LIB pure_quanta
J 0
(-6175 5975);
DISPLAY INVISIBLE (-6175 5975);
FORCEPROP 1 LAST PATH I7
J 0
(-6225 6125);
DISPLAY 0.978723 (-6225 6125);
PAINT WHITE (-6225 6125);
DISPLAY INVISIBLE (-6225 6125);
FORCEPROP 0 LAST CDS_LOCATION R3108
J 0
(-6250 6025);
DISPLAY 1.021277 (-6250 6025);
DISPLAY INVISIBLE (-6250 6025);
FORCEPROP 0 LAST $SEC 1
J 0
(-6250 6025);
DISPLAY 0.680851 (-6250 6025);
PAINT MONO (-6250 6025);
DISPLAY INVISIBLE (-6250 6025);
FORCEPROP 0 LAST CDS_SEC 1
J 0
(-6250 6025);
DISPLAY 1.021277 (-6250 6025);
DISPLAY INVISIBLE (-6250 6025);
FORCEADD OFFPAGE..2
(-1275 8700);
FORCEPROP 2 LAST $XR0 140 
J 0
(-1086 8700);
DISPLAY 0.638298 (-1086 8700);
PAINT MONO (-1086 8700);
FORCEPROP 2 LAST CDS_LIB standard
J 0
(-1275 8700);
DISPLAY INVISIBLE (-1275 8700);
FORCEPROP 1 LAST OFFPAGE TRUE
J 0
(-950 8575);
DISPLAY 0.872340 (-950 8575);
PAINT GREEN (-950 8575);
DISPLAY INVISIBLE (-950 8575);
FORCEPROP 1 LAST COMMENT_BODY TRUE
J 0
(-1320 8605);
DISPLAY 0.872340 (-1320 8605);
PAINT GREEN (-1320 8605);
DISPLAY INVISIBLE (-1320 8605);
FORCEPROP 2 LAST PATH I70
J 0
(-1075 8750);
DISPLAY 1.021277 (-1075 8750);
DISPLAY INVISIBLE (-1075 8750);
FORCEADD Q_RES..1
(-150 4550);
FORCEPROP 1 LAST PART_NUMBER CS02742FB03
J 0
(-250 4450);
DISPLAY 0.404255 (-250 4450);
DISPLAY INVISIBLE (-250 4450);
FORCEPROP 1 LAST WATTAGE 1/16W
J 2
(-25 4500);
DISPLAY 0.404255 (-25 4500);
FORCEPROP 1 LAST PACK_TYPE 0402LF
J 0
(-250 4500);
DISPLAY 0.404255 (-250 4500);
FORCEPROP 1 LAST MATERIAL CHIP
J 0
(150 4550);
DISPLAY 0.510638 (150 4550);
FORCEPROP 1 LAST TOLERANCE 1%
J 0
(75 4550);
DISPLAY 0.510638 (75 4550);
FORCEPROP 1 LAST VALUE 27.4
J 2
(50 4550);
DISPLAY 0.510638 (50 4550);
FORCEPROP 1 LAST $LOCATION R2674
J 0
(-375 4550);
DISPLAY 0.638298 (-375 4550);
FORCEPROP 1 LASTPIN (-250 4550) $PN 1
J 0
(-238 4562);
DISPLAY 0.787234 (-238 4562);
PAINT MONO (-238 4562);
FORCEPROP 1 LASTPIN (-50 4550) $PN 2
J 0
(-88 4562);
DISPLAY 0.787234 (-88 4562);
PAINT MONO (-88 4562);
FORCEPROP 2 LAST CDS_LIB pure_quanta
J 0
(-150 4550);
DISPLAY INVISIBLE (-150 4550);
FORCEPROP 1 LAST PATH I71
J 0
(-200 4700);
DISPLAY 0.978723 (-200 4700);
PAINT WHITE (-200 4700);
DISPLAY INVISIBLE (-200 4700);
FORCEPROP 0 LAST CDS_LOCATION R2674
J 0
(-50 4675);
DISPLAY 1.021277 (-50 4675);
DISPLAY INVISIBLE (-50 4675);
FORCEPROP 0 LAST $SEC 1
J 0
(-50 4675);
DISPLAY 0.680851 (-50 4675);
PAINT MONO (-50 4675);
DISPLAY INVISIBLE (-50 4675);
FORCEPROP 0 LAST CDS_SEC 1
J 0
(-50 4675);
DISPLAY 1.021277 (-50 4675);
DISPLAY INVISIBLE (-50 4675);
FORCEADD Q_RES..1
(-150 4650);
FORCEPROP 1 LAST PART_NUMBER CS03322FB03
J 0
(-275 4700);
DISPLAY 0.404255 (-275 4700);
DISPLAY INVISIBLE (-275 4700);
FORCEPROP 1 LAST MATERIAL CHIP
J 0
(150 4650);
DISPLAY 0.510638 (150 4650);
FORCEPROP 1 LAST TOLERANCE 1%
J 0
(75 4650);
DISPLAY 0.510638 (75 4650);
FORCEPROP 1 LAST VALUE 33.2
J 2
(50 4650);
DISPLAY 0.510638 (50 4650);
FORCEPROP 1 LAST $LOCATION R2675
J 0
(-375 4650);
DISPLAY 0.638298 (-375 4650);
FORCEPROP 1 LASTPIN (-250 4650) $PN 1
J 0
(-238 4662);
DISPLAY 0.787234 (-238 4662);
PAINT MONO (-238 4662);
FORCEPROP 1 LASTPIN (-50 4650) $PN 2
J 0
(-88 4662);
DISPLAY 0.787234 (-88 4662);
PAINT MONO (-88 4662);
FORCEPROP 2 LAST CDS_LIB pure_quanta
J 0
(-150 4650);
DISPLAY INVISIBLE (-150 4650);
FORCEPROP 1 LAST PACK_TYPE 0402LF
J 0
(-275 4750);
DISPLAY 0.404255 (-275 4750);
DISPLAY INVISIBLE (-275 4750);
FORCEPROP 1 LAST WATTAGE 1/16W
J 2
(-50 4750);
DISPLAY 0.404255 (-50 4750);
DISPLAY INVISIBLE (-50 4750);
FORCEPROP 1 LAST PATH I72
J 0
(-200 4800);
DISPLAY 0.978723 (-200 4800);
PAINT WHITE (-200 4800);
DISPLAY INVISIBLE (-200 4800);
FORCEPROP 0 LAST CDS_LOCATION R2675
J 0
(-375 4700);
DISPLAY 1.021277 (-375 4700);
DISPLAY INVISIBLE (-375 4700);
FORCEPROP 0 LAST $SEC 1
J 0
(-375 4700);
DISPLAY 0.680851 (-375 4700);
PAINT MONO (-375 4700);
DISPLAY INVISIBLE (-375 4700);
FORCEPROP 0 LAST CDS_SEC 1
J 0
(-375 4700);
DISPLAY 1.021277 (-375 4700);
DISPLAY INVISIBLE (-375 4700);
FORCEADD OFFPAGE..3
(1175 4550);
FORCEPROP 2 LAST $XR0 137 
J 0
(1389 4550);
DISPLAY 0.638298 (1389 4550);
PAINT MONO (1389 4550);
FORCEPROP 2 LAST CDS_LIB standard
J 0
(1175 4550);
PAINT MONO (1175 4550);
DISPLAY INVISIBLE (1175 4550);
FORCEPROP 1 LAST OFFPAGE TRUE
J 0
(1500 4425);
DISPLAY 0.872340 (1500 4425);
PAINT GREEN (1500 4425);
DISPLAY INVISIBLE (1500 4425);
FORCEPROP 1 LAST COMMENT_BODY TRUE
J 0
(1125 4450);
DISPLAY 0.872340 (1125 4450);
PAINT GREEN (1125 4450);
DISPLAY INVISIBLE (1125 4450);
FORCEPROP 2 LAST PATH I73
J 0
(1400 4600);
DISPLAY 1.021277 (1400 4600);
DISPLAY INVISIBLE (1400 4600);
FORCEADD OFFPAGE..2
(1175 4650);
FORCEPROP 2 LAST $XR0 137 
J 0
(1364 4650);
DISPLAY 0.638298 (1364 4650);
PAINT MONO (1364 4650);
FORCEPROP 2 LAST CDS_LIB standard
J 0
(1175 4650);
DISPLAY INVISIBLE (1175 4650);
FORCEPROP 1 LAST OFFPAGE TRUE
J 0
(1500 4525);
DISPLAY 0.872340 (1500 4525);
PAINT GREEN (1500 4525);
DISPLAY INVISIBLE (1500 4525);
FORCEPROP 1 LAST COMMENT_BODY TRUE
J 0
(1130 4555);
DISPLAY 0.872340 (1130 4555);
PAINT GREEN (1130 4555);
DISPLAY INVISIBLE (1130 4555);
FORCEPROP 2 LAST PATH I74
J 0
(1375 4700);
DISPLAY 1.021277 (1375 4700);
DISPLAY INVISIBLE (1375 4700);
FORCEADD Q_RES..2
(-700 5025);
FORCEPROP 1 LAST PART_NUMBER CS24702JB10
J 0
(-660 4850);
DISPLAY 0.638298 (-660 4850);
DISPLAY INVISIBLE (-660 4850);
FORCEPROP 1 LAST WATTAGE 1/16W
J 0
(-660 5000);
DISPLAY 0.638298 (-660 5000);
FORCEPROP 1 LAST MATERIAL EMPTY
J 0
(-660 4950);
DISPLAY 0.638298 (-660 4950);
PAINT RED (-660 4950);
FORCEPROP 1 LAST PACK_TYPE 0402LF
J 0
(-660 4900);
DISPLAY 0.638298 (-660 4900);
FORCEPROP 1 LAST TOLERANCE 5%
J 0
(-655 5050);
DISPLAY 0.638298 (-655 5050);
FORCEPROP 1 LAST VALUE 4.7K
J 0
(-655 5100);
DISPLAY 0.638298 (-655 5100);
FORCEPROP 1 LAST $LOCATION R2668
J 0
(-655 5150);
DISPLAY 0.638298 (-655 5150);
FORCEPROP 1 LASTPIN (-700 5125) $PN 1
J 0
(-695 5087);
DISPLAY 0.787234 (-695 5087);
FORCEPROP 1 LASTPIN (-700 4925) $PN 2
J 0
(-695 4935);
DISPLAY 0.787234 (-695 4935);
FORCEPROP 2 LAST CDS_LIB pure_quanta
J 0
(-700 5025);
PAINT MONO (-700 5025);
DISPLAY INVISIBLE (-700 5025);
FORCEPROP 1 LAST PATH I75
J 0
(-650 5200);
DISPLAY 0.978723 (-650 5200);
PAINT WHITE (-650 5200);
DISPLAY INVISIBLE (-650 5200);
FORCEPROP 2 LAST CDS_LOCATION R2668
J 0
(-650 5250);
DISPLAY 1.021277 (-650 5250);
DISPLAY INVISIBLE (-650 5250);
FORCEPROP 2 LAST $SEC 1
J 0
(-650 5250);
DISPLAY 0.680851 (-650 5250);
PAINT MONO (-650 5250);
DISPLAY INVISIBLE (-650 5250);
FORCEPROP 2 LAST CDS_SEC 1
J 0
(-650 5250);
DISPLAY 1.021277 (-650 5250);
DISPLAY INVISIBLE (-650 5250);
FORCEADD UNIVERSAL_POWER..1
(-700 5350);
FORCEPROP 3 LASTPIN (-700 5300) SIG_NAME P3V3_AUX\g
J 0
(-690 5310);
DISPLAY 0.659574 (-690 5310);
PAINT MONO (-690 5310);
DISPLAY INVISIBLE (-690 5310);
FORCEPROP 1 LAST HDL_POWER P3V3_AUX
J 1
(-700 5400);
DISPLAY 0.872340 (-700 5400);
PAINT GREEN (-700 5400);
FORCEPROP 2 LAST CDS_LIB logical_power
J 0
(-700 5350);
PAINT MONO (-700 5350);
DISPLAY INVISIBLE (-700 5350);
FORCEPROP 1 LAST PATH I76
J 0
(-650 5375);
DISPLAY 0.872340 (-650 5375);
PAINT AQUA (-650 5375);
DISPLAY INVISIBLE (-650 5375);
FORCEADD Q_RES..2
(-450 5025);
FORCEPROP 1 LAST PART_NUMBER CS24702JB10
J 0
(-410 4850);
DISPLAY 0.638298 (-410 4850);
DISPLAY INVISIBLE (-410 4850);
FORCEPROP 1 LAST TOLERANCE 5%
J 0
(-405 5050);
DISPLAY 0.638298 (-405 5050);
FORCEPROP 1 LAST VALUE 4.7K
J 0
(-405 5100);
DISPLAY 0.638298 (-405 5100);
FORCEPROP 1 LAST WATTAGE 1/16W
J 0
(-410 5000);
DISPLAY 0.638298 (-410 5000);
FORCEPROP 1 LAST MATERIAL EMPTY
J 0
(-410 4950);
DISPLAY 0.638298 (-410 4950);
PAINT RED (-410 4950);
FORCEPROP 1 LAST PACK_TYPE 0402LF
J 0
(-425 4900);
DISPLAY 0.638298 (-425 4900);
FORCEPROP 1 LAST $LOCATION R2670
J 0
(-405 5150);
DISPLAY 0.638298 (-405 5150);
FORCEPROP 1 LASTPIN (-450 5125) $PN 1
J 0
(-445 5087);
DISPLAY 0.787234 (-445 5087);
FORCEPROP 1 LASTPIN (-450 4925) $PN 2
J 0
(-445 4935);
DISPLAY 0.787234 (-445 4935);
FORCEPROP 2 LAST CDS_LIB pure_quanta
J 0
(-450 5025);
PAINT MONO (-450 5025);
DISPLAY INVISIBLE (-450 5025);
FORCEPROP 1 LAST PATH I77
J 0
(-400 5200);
DISPLAY 0.978723 (-400 5200);
PAINT WHITE (-400 5200);
DISPLAY INVISIBLE (-400 5200);
FORCEPROP 2 LAST CDS_LOCATION R2670
J 0
(-400 5250);
DISPLAY 1.021277 (-400 5250);
DISPLAY INVISIBLE (-400 5250);
FORCEPROP 2 LAST $SEC 1
J 0
(-400 5250);
DISPLAY 0.680851 (-400 5250);
PAINT MONO (-400 5250);
DISPLAY INVISIBLE (-400 5250);
FORCEPROP 2 LAST CDS_SEC 1
J 0
(-400 5250);
DISPLAY 1.021277 (-400 5250);
DISPLAY INVISIBLE (-400 5250);
FORCEADD Q_RES..1
(-225 7425);
FORCEPROP 1 LAST PART_NUMBER CS03322FB03
J 0
(-350 7475);
DISPLAY 0.404255 (-350 7475);
DISPLAY INVISIBLE (-350 7475);
FORCEPROP 1 LAST MATERIAL CHIP
J 0
(75 7425);
DISPLAY 0.510638 (75 7425);
FORCEPROP 1 LAST VALUE 33.2
J 2
(-25 7425);
DISPLAY 0.510638 (-25 7425);
FORCEPROP 1 LAST TOLERANCE 1%
J 0
(0 7425);
DISPLAY 0.510638 (0 7425);
FORCEPROP 1 LAST PACK_TYPE 0402LF
J 0
(-350 7525);
DISPLAY 0.404255 (-350 7525);
FORCEPROP 1 LAST WATTAGE 1/16W
J 2
(-125 7525);
DISPLAY 0.404255 (-125 7525);
FORCEPROP 1 LAST $LOCATION R2897
J 0
(-450 7425);
DISPLAY 0.638298 (-450 7425);
FORCEPROP 1 LASTPIN (-325 7425) $PN 1
J 0
(-313 7437);
DISPLAY 0.787234 (-313 7437);
PAINT MONO (-313 7437);
FORCEPROP 1 LASTPIN (-125 7425) $PN 2
J 0
(-163 7437);
DISPLAY 0.787234 (-163 7437);
PAINT MONO (-163 7437);
FORCEPROP 2 LAST CDS_LIB pure_quanta
J 0
(-225 7425);
DISPLAY INVISIBLE (-225 7425);
FORCEPROP 1 LAST PATH I78
J 0
(-275 7575);
DISPLAY 0.978723 (-275 7575);
PAINT WHITE (-275 7575);
DISPLAY INVISIBLE (-275 7575);
FORCEPROP 0 LAST CDS_LOCATION R2897
J 0
(-125 7550);
DISPLAY 1.021277 (-125 7550);
DISPLAY INVISIBLE (-125 7550);
FORCEPROP 0 LAST $SEC 1
J 0
(-125 7550);
DISPLAY 0.680851 (-125 7550);
PAINT MONO (-125 7550);
DISPLAY INVISIBLE (-125 7550);
FORCEPROP 0 LAST CDS_SEC 1
J 0
(-125 7550);
DISPLAY 1.021277 (-125 7550);
DISPLAY INVISIBLE (-125 7550);
FORCEADD Q_RES..1
(-225 7325);
FORCEPROP 1 LAST PART_NUMBER CS03322FB03
J 0
(-350 7375);
DISPLAY 0.404255 (-350 7375);
DISPLAY INVISIBLE (-350 7375);
FORCEPROP 1 LAST TOLERANCE 1%
J 0
(0 7325);
DISPLAY 0.510638 (0 7325);
FORCEPROP 1 LAST MATERIAL CHIP
J 0
(75 7325);
DISPLAY 0.510638 (75 7325);
FORCEPROP 1 LAST VALUE 33.2
J 2
(-25 7325);
DISPLAY 0.510638 (-25 7325);
FORCEPROP 1 LAST $LOCATION R2898
J 0
(-450 7325);
DISPLAY 0.638298 (-450 7325);
FORCEPROP 1 LASTPIN (-325 7325) $PN 1
J 0
(-313 7337);
DISPLAY 0.787234 (-313 7337);
PAINT MONO (-313 7337);
FORCEPROP 1 LASTPIN (-125 7325) $PN 2
J 0
(-163 7337);
DISPLAY 0.787234 (-163 7337);
PAINT MONO (-163 7337);
FORCEPROP 1 LAST WATTAGE 1/16W
J 2
(-125 7425);
DISPLAY 0.404255 (-125 7425);
DISPLAY INVISIBLE (-125 7425);
FORCEPROP 1 LAST PACK_TYPE 0402LF
J 0
(-350 7425);
DISPLAY 0.404255 (-350 7425);
DISPLAY INVISIBLE (-350 7425);
FORCEPROP 2 LAST CDS_LIB pure_quanta
J 0
(-225 7325);
DISPLAY INVISIBLE (-225 7325);
FORCEPROP 1 LAST PATH I79
J 0
(-275 7475);
DISPLAY 0.978723 (-275 7475);
PAINT WHITE (-275 7475);
DISPLAY INVISIBLE (-275 7475);
FORCEPROP 0 LAST CDS_LOCATION R2898
J 0
(-450 7375);
DISPLAY 1.021277 (-450 7375);
DISPLAY INVISIBLE (-450 7375);
FORCEPROP 0 LAST $SEC 1
J 0
(-450 7375);
DISPLAY 0.680851 (-450 7375);
PAINT MONO (-450 7375);
DISPLAY INVISIBLE (-450 7375);
FORCEPROP 0 LAST CDS_SEC 1
J 0
(-450 7375);
DISPLAY 1.021277 (-450 7375);
DISPLAY INVISIBLE (-450 7375);
FORCEADD Q_RES..1
(-6175 6075);
FORCEPROP 1 LAST PART_NUMBER CS00002JB13
J 0
(-6200 6000);
DISPLAY 0.404255 (-6200 6000);
DISPLAY INVISIBLE (-6200 6000);
FORCEPROP 1 LAST MATERIAL CHIP
J 0
(-5925 6075);
DISPLAY 0.510638 (-5925 6075);
FORCEPROP 1 LAST TOLERANCE 5%
J 0
(-5975 6075);
DISPLAY 0.510638 (-5975 6075);
FORCEPROP 1 LAST VALUE 0
J 2
(-6025 6075);
DISPLAY 0.510638 (-6025 6075);
FORCEPROP 1 LAST $LOCATION R3107
J 0
(-6325 6050);
DISPLAY 0.510638 (-6325 6050);
FORCEPROP 1 LASTPIN (-6275 6075) $PN 1
J 0
(-6263 6087);
DISPLAY 0.787234 (-6263 6087);
PAINT MONO (-6263 6087);
FORCEPROP 1 LASTPIN (-6075 6075) $PN 2
J 0
(-6113 6087);
DISPLAY 0.787234 (-6113 6087);
PAINT MONO (-6113 6087);
FORCEPROP 2 LAST CDS_LIB pure_quanta
J 0
(-6175 6075);
DISPLAY INVISIBLE (-6175 6075);
FORCEPROP 1 LAST WATTAGE 1/16W
J 2
(-6025 6025);
DISPLAY 0.404255 (-6025 6025);
DISPLAY INVISIBLE (-6025 6025);
FORCEPROP 1 LAST PACK_TYPE 0402LF
J 0
(-6325 6025);
DISPLAY 0.404255 (-6325 6025);
DISPLAY INVISIBLE (-6325 6025);
FORCEPROP 1 LAST PATH I8
J 0
(-6225 6225);
DISPLAY 0.978723 (-6225 6225);
PAINT WHITE (-6225 6225);
DISPLAY INVISIBLE (-6225 6225);
FORCEPROP 0 LAST CDS_LOCATION R3107
J 0
(-6250 6125);
DISPLAY 1.021277 (-6250 6125);
DISPLAY INVISIBLE (-6250 6125);
FORCEPROP 0 LAST $SEC 1
J 0
(-6250 6125);
DISPLAY 0.680851 (-6250 6125);
PAINT MONO (-6250 6125);
DISPLAY INVISIBLE (-6250 6125);
FORCEPROP 0 LAST CDS_SEC 1
J 0
(-6250 6125);
DISPLAY 1.021277 (-6250 6125);
DISPLAY INVISIBLE (-6250 6125);
FORCEADD Q_RES..2
(-775 7750);
FORCEPROP 1 LAST PART_NUMBER CS35492FB03
J 0
(-735 7625);
DISPLAY 0.404255 (-735 7625);
DISPLAY INVISIBLE (-735 7625);
FORCEPROP 1 LAST PACK_TYPE 0402LF
J 0
(-735 7575);
DISPLAY 0.404255 (-735 7575);
FORCEPROP 1 LAST VALUE 54.9K
J 0
(-730 7825);
DISPLAY 0.404255 (-730 7825);
FORCEPROP 1 LAST TOLERANCE 1%
J 0
(-730 7775);
DISPLAY 0.404255 (-730 7775);
FORCEPROP 1 LAST WATTAGE 1/16W
J 0
(-735 7725);
DISPLAY 0.404255 (-735 7725);
FORCEPROP 1 LAST MATERIAL CHIP
J 0
(-735 7675);
DISPLAY 0.404255 (-735 7675);
FORCEPROP 1 LAST $LOCATION R3523
J 0
(-730 7875);
DISPLAY 0.510638 (-730 7875);
FORCEPROP 1 LASTPIN (-775 7850) $PN 1
J 0
(-770 7812);
DISPLAY 0.787234 (-770 7812);
PAINT MONO (-770 7812);
FORCEPROP 1 LASTPIN (-775 7650) $PN 2
J 0
(-770 7660);
DISPLAY 0.787234 (-770 7660);
PAINT MONO (-770 7660);
FORCEPROP 2 LAST CDS_LIB pure_quanta
J 0
(-775 7750);
DISPLAY INVISIBLE (-775 7750);
FORCEPROP 1 LAST PATH I80
J 0
(-725 7925);
DISPLAY 0.978723 (-725 7925);
PAINT WHITE (-725 7925);
DISPLAY INVISIBLE (-725 7925);
FORCEPROP 0 LAST CDS_LOCATION R3523
J 0
(-725 7900);
DISPLAY 1.021277 (-725 7900);
DISPLAY INVISIBLE (-725 7900);
FORCEPROP 0 LAST $SEC 1
J 0
(-725 7900);
DISPLAY 0.680851 (-725 7900);
PAINT MONO (-725 7900);
DISPLAY INVISIBLE (-725 7900);
FORCEPROP 0 LAST CDS_SEC 1
J 0
(-725 7900);
DISPLAY 1.021277 (-725 7900);
DISPLAY INVISIBLE (-725 7900);
FORCEADD Q_RES..2
(-525 7750);
FORCEPROP 1 LAST PART_NUMBER CS35492FB03
J 0
(-485 7625);
DISPLAY 0.404255 (-485 7625);
DISPLAY INVISIBLE (-485 7625);
FORCEPROP 1 LAST MATERIAL CHIP
J 0
(-485 7675);
DISPLAY 0.404255 (-485 7675);
FORCEPROP 1 LAST WATTAGE 1/16W
J 0
(-485 7725);
DISPLAY 0.404255 (-485 7725);
FORCEPROP 1 LAST TOLERANCE 1%
J 0
(-480 7775);
DISPLAY 0.404255 (-480 7775);
FORCEPROP 1 LAST VALUE 54.9K
J 0
(-480 7825);
DISPLAY 0.404255 (-480 7825);
FORCEPROP 1 LAST PACK_TYPE 0402LF
J 0
(-485 7575);
DISPLAY 0.404255 (-485 7575);
FORCEPROP 1 LAST $LOCATION R3524
J 0
(-480 7875);
DISPLAY 0.978723 (-480 7875);
FORCEPROP 1 LASTPIN (-525 7850) $PN 1
J 0
(-520 7812);
DISPLAY 0.787234 (-520 7812);
PAINT MONO (-520 7812);
FORCEPROP 1 LASTPIN (-525 7650) $PN 2
J 0
(-520 7660);
DISPLAY 0.787234 (-520 7660);
PAINT MONO (-520 7660);
FORCEPROP 2 LAST CDS_LIB pure_quanta
J 0
(-525 7750);
DISPLAY INVISIBLE (-525 7750);
FORCEPROP 1 LAST PATH I81
J 0
(-475 7925);
DISPLAY 0.978723 (-475 7925);
PAINT WHITE (-475 7925);
DISPLAY INVISIBLE (-475 7925);
FORCEPROP 0 LAST CDS_LOCATION R3524
J 0
(-475 7925);
DISPLAY 1.021277 (-475 7925);
DISPLAY INVISIBLE (-475 7925);
FORCEPROP 0 LAST $SEC 1
J 0
(-475 7925);
DISPLAY 0.680851 (-475 7925);
PAINT MONO (-475 7925);
DISPLAY INVISIBLE (-475 7925);
FORCEPROP 0 LAST CDS_SEC 1
J 0
(-475 7925);
DISPLAY 1.021277 (-475 7925);
DISPLAY INVISIBLE (-475 7925);
FORCEADD UNIVERSAL_POWER..1
(-775 8075);
FORCEPROP 3 LASTPIN (-775 8025) SIG_NAME P3V3_AUX\g
J 0
(-765 8035);
DISPLAY 0.659574 (-765 8035);
PAINT MONO (-765 8035);
DISPLAY INVISIBLE (-765 8035);
FORCEPROP 1 LAST HDL_POWER P3V3_AUX
J 1
(-775 8125);
DISPLAY 0.872340 (-775 8125);
PAINT GREEN (-775 8125);
FORCEPROP 2 LAST CDS_LIB logical_power
J 0
(-775 8075);
PAINT MONO (-775 8075);
DISPLAY INVISIBLE (-775 8075);
FORCEPROP 1 LAST PATH I82
J 0
(-725 8100);
DISPLAY 0.872340 (-725 8100);
PAINT AQUA (-725 8100);
DISPLAY INVISIBLE (-725 8100);
FORCEADD OFFPAGE..2
(1100 7325);
FORCEPROP 2 LAST $XR0 143 
J 0
(1289 7325);
DISPLAY 0.638298 (1289 7325);
PAINT MONO (1289 7325);
FORCEPROP 2 LAST CDS_LIB standard
J 0
(1100 7325);
DISPLAY INVISIBLE (1100 7325);
FORCEPROP 1 LAST OFFPAGE TRUE
J 0
(1425 7200);
DISPLAY 0.872340 (1425 7200);
PAINT GREEN (1425 7200);
DISPLAY INVISIBLE (1425 7200);
FORCEPROP 1 LAST COMMENT_BODY TRUE
J 0
(1055 7230);
DISPLAY 0.872340 (1055 7230);
PAINT GREEN (1055 7230);
DISPLAY INVISIBLE (1055 7230);
FORCEPROP 2 LAST PATH I83
J 0
(1300 7375);
DISPLAY 1.021277 (1300 7375);
DISPLAY INVISIBLE (1300 7375);
FORCEADD OFFPAGE..3
(1100 7425);
FORCEPROP 2 LAST $XR0 143 
J 0
(1314 7425);
DISPLAY 0.638298 (1314 7425);
PAINT MONO (1314 7425);
FORCEPROP 2 LAST CDS_LIB standard
J 0
(1100 7425);
PAINT MONO (1100 7425);
DISPLAY INVISIBLE (1100 7425);
FORCEPROP 1 LAST OFFPAGE TRUE
J 0
(1425 7300);
DISPLAY 0.872340 (1425 7300);
PAINT GREEN (1425 7300);
DISPLAY INVISIBLE (1425 7300);
FORCEPROP 1 LAST COMMENT_BODY TRUE
J 0
(1050 7325);
DISPLAY 0.872340 (1050 7325);
PAINT GREEN (1050 7325);
DISPLAY INVISIBLE (1050 7325);
FORCEPROP 2 LAST PATH I84
J 0
(1325 7475);
DISPLAY 1.021277 (1325 7475);
DISPLAY INVISIBLE (1325 7475);
FORCEADD Q_RES..1
(-6175 6175);
FORCEPROP 1 LAST PART_NUMBER CS00002JB13
J 0
(-6275 6100);
DISPLAY 0.404255 (-6275 6100);
DISPLAY INVISIBLE (-6275 6100);
FORCEPROP 1 LAST MATERIAL CHIP
J 0
(-5900 6175);
DISPLAY 0.510638 (-5900 6175);
FORCEPROP 1 LAST VALUE 0
J 2
(-6000 6175);
DISPLAY 0.510638 (-6000 6175);
FORCEPROP 1 LAST TOLERANCE 5%
J 0
(-5950 6175);
DISPLAY 0.510638 (-5950 6175);
FORCEPROP 1 LAST $LOCATION R2992
J 0
(-6375 6175);
DISPLAY 0.638298 (-6375 6175);
FORCEPROP 1 LASTPIN (-6275 6175) $PN 1
J 0
(-6263 6187);
DISPLAY 0.787234 (-6263 6187);
PAINT MONO (-6263 6187);
FORCEPROP 1 LASTPIN (-6075 6175) $PN 2
J 0
(-6113 6187);
DISPLAY 0.787234 (-6113 6187);
PAINT MONO (-6113 6187);
FORCEPROP 2 LAST CDS_LIB pure_quanta
J 0
(-6175 6175);
DISPLAY INVISIBLE (-6175 6175);
FORCEPROP 1 LAST PACK_TYPE 0402LF
J 0
(-6275 6125);
DISPLAY 0.404255 (-6275 6125);
DISPLAY INVISIBLE (-6275 6125);
FORCEPROP 1 LAST WATTAGE 1/16W
J 2
(-6075 6125);
DISPLAY 0.404255 (-6075 6125);
DISPLAY INVISIBLE (-6075 6125);
FORCEPROP 1 LAST PATH I9
J 0
(-6225 6325);
DISPLAY 0.978723 (-6225 6325);
PAINT WHITE (-6225 6325);
DISPLAY INVISIBLE (-6225 6325);
FORCEPROP 0 LAST CDS_LOCATION R2992
J 0
(-6050 6275);
DISPLAY 1.021277 (-6050 6275);
DISPLAY INVISIBLE (-6050 6275);
FORCEPROP 0 LAST $SEC 1
J 0
(-6050 6275);
DISPLAY 0.680851 (-6050 6275);
PAINT MONO (-6050 6275);
DISPLAY INVISIBLE (-6050 6275);
FORCEPROP 0 LAST CDS_SEC 1
J 0
(-6050 6275);
DISPLAY 1.021277 (-6050 6275);
DISPLAY INVISIBLE (-6050 6275);
FORCEADD QUANTA_TITLE_BLOCK_C..1
(1850 3425);
FORCEPROP 0 LAST CDS_CON_LAST_MODIFIED Fri Aug 25 14:03:58 2023
J 0
(-35 3440);
PAINT MONO (-35 3440);
DISPLAY INVISIBLE (-35 3440);
FORCEPROP 2 LAST CUSTOM_TXT_CDS <XR_PAGE_TITLE>
J 0
(-6040 8675);
DISPLAY 0.638298 (-6040 8675);
PAINT PINK (-6040 8675);
DISPLAY INVISIBLE (-6040 8675);
FORCEPROP 2 LAST CUSTOM_TXT_CDS <CON_LAST_MODIFIED>
J 0
(-35 3440);
DISPLAY 0.978723 (-35 3440);
FORCEPROP 2 LAST CUSTOM_TXT_CDS <NAME_1>
J 0
(-1325 3600);
FORCEPROP 2 LAST CUSTOM_TXT_CDS <NAME_2>
J 0
(-1325 3475);
FORCEPROP 2 LAST CUSTOM_TXT_CDS <Q_PROJ>
J 0
(-532 3527);
DISPLAY 1.212766 (-532 3527);
FORCEPROP 2 LAST CUSTOM_TXT_CDS <Q_REV>
J 0
(1666 3528);
DISPLAY 1.212766 (1666 3528);
FORCEPROP 2 LAST CUSTOM_TXT_CDS <CON_PAGE_NUM> OF <CON_TOTAL_PAGES>
J 0
(1404 3443);
DISPLAY 0.978723 (1404 3443);
FORCEPROP 2 LAST CUSTOM_TXT_CDS <Q_NUMBER>
J 0
(447 3528);
DISPLAY 1.212766 (447 3528);
FORCEPROP 1 LAST Q_TITLE SMBUS - PCIE3  SMBUS
J 0
(-7416 3451);
DISPLAY 2.446809 (-7416 3451);
PAINT GREEN (-7416 3451);
FORCEPROP 1 LAST Q_DEPT 
J 1
(-1913 3474);
DISPLAY 1.957447 (-1913 3474);
PAINT GREEN (-1913 3474);
FORCEPROP 2 LAST CDS_XR_PAGE_TITLE CR-234 : @S9S_MB_2U_LIB.S9S_MB_2U(SCH_1):PAGE234
J 0
(-6040 8675);
DISPLAY 0.638298 (-6040 8675);
PAINT PINK (-6040 8675);
DISPLAY INVISIBLE (-6040 8675);
FORCEPROP 1 LAST COMMENT_BODY TRUE
J 0
(1862 3412);
DISPLAY 0.978723 (1862 3412);
PAINT GREEN (1862 3412);
DISPLAY INVISIBLE (1862 3412);
FORCEPROP 2 LAST PAGE_BORDER TRUE
J 0
(-6040 8675);
DISPLAY 0.638298 (-6040 8675);
PAINT PINK (-6040 8675);
DISPLAY INVISIBLE (-6040 8675);
FORCEPROP 1 LAST CDS_LMAN_SYM_OUTLINE -9475,6775,100,-125
J 0
(1850 3425);
DISPLAY 0.468085 (1850 3425);
PAINT GREEN (1850 3425);
DISPLAY INVISIBLE (1850 3425);
FORCEPROP 2 LAST CDS_LIB pure_quanta
J 0
(1850 3425);
PAINT MONO (1850 3425);
DISPLAY INVISIBLE (1850 3425);
FORCEADD DNS..2
(-1625 5025);
PAINT RED (-1625 5025);
FORCEPROP 1 LAST COMMENT_BODY TRUE
J 0
(-1625 5025);
DISPLAY INVISIBLE (-1625 5025);
FORCEPROP 2 LAST CDS_LIB mstr_misc
J 0
(-1625 5025);
DISPLAY INVISIBLE (-1625 5025);
FORCEADD DNS..2
(-700 5000);
PAINT RED (-700 5000);
FORCEPROP 2 LAST CDS_LIB mstr_misc
J 0
(-700 5000);
DISPLAY INVISIBLE (-700 5000);
FORCEPROP 1 LAST COMMENT_BODY TRUE
J 0
(-700 5000);
DISPLAY INVISIBLE (-700 5000);
FORCEADD DNS..2
(-4875 5575);
PAINT RED (-4875 5575);
FORCEPROP 2 LAST CDS_LIB mstr_misc
J 0
(-4875 5575);
DISPLAY INVISIBLE (-4875 5575);
FORCEPROP 1 LAST COMMENT_BODY TRUE
J 0
(-4875 5575);
DISPLAY INVISIBLE (-4875 5575);
FORCEADD DNS..2
(-2300 4600);
PAINT RED (-2300 4600);
FORCEPROP 2 LAST CDS_LIB mstr_misc
J 0
(-2300 4600);
DISPLAY INVISIBLE (-2300 4600);
FORCEPROP 1 LAST COMMENT_BODY TRUE
J 0
(-2300 4600);
DISPLAY INVISIBLE (-2300 4600);
FORCEADD DNS..2
(-2275 6925);
PAINT RED (-2275 6925);
FORCEPROP 2 LAST CDS_LIB mstr_misc
J 0
(-2275 6925);
DISPLAY INVISIBLE (-2275 6925);
FORCEPROP 1 LAST COMMENT_BODY TRUE
J 0
(-2275 6925);
DISPLAY INVISIBLE (-2275 6925);
FORCEADD DNS..2
(-4650 8300);
PAINT RED (-4650 8300);
FORCEPROP 2 LAST CDS_LIB mstr_misc
J 0
(-4650 8300);
DISPLAY INVISIBLE (-4650 8300);
FORCEPROP 1 LAST COMMENT_BODY TRUE
J 0
(-4650 8300);
DISPLAY INVISIBLE (-4650 8300);
FORCEADD DNS..2
(-450 5000);
PAINT RED (-450 5000);
FORCEPROP 2 LAST CDS_LIB mstr_misc
J 0
(-450 5000);
DISPLAY INVISIBLE (-450 5000);
FORCEPROP 1 LAST COMMENT_BODY TRUE
J 0
(-450 5000);
DISPLAY INVISIBLE (-450 5000);
WIRE 16 -1 (-4300 6600)(-4300 6675);
WIRE 16 -1 (-4300 6600)(-4300 6175);
WIRE 16 -1 (-4300 6600)(-4125 6600);
WIRE 16 -1 (-3375 6625)(-3375 6675);
WIRE 16 -1 (-3375 6625)(-3125 6625);
WIRE 16 -1 (-3375 6500)(-3375 6625);
WIRE 16 -1 (-1800 5225)(-1800 5300);
WIRE 16 -1 (-1800 5225)(-1725 5225);
WIRE 16 -1 (-4175 9325)(-4175 9400);
WIRE 16 -1 (-4175 9325)(-4175 8900);
WIRE 16 -1 (-4175 9325)(-4000 9325);
WIRE 16 -1 (-3150 9350)(-3150 9400);
WIRE 16 -1 (-3150 9350)(-2900 9350);
WIRE 16 -1 (-3150 9225)(-3150 9350);
WIRE 16 -1 (-1700 7950)(-1700 8025);
WIRE 16 -1 (-1700 7950)(-1700 7525);
WIRE 16 -1 (-1700 7950)(-1525 7950);
WIRE 16 -1 (-700 5250)(-700 5300);
WIRE 16 -1 (-700 5250)(-450 5250);
WIRE 16 -1 (-700 5125)(-700 5250);
WIRE 16 -1 (-775 7975)(-775 8025);
WIRE 16 -1 (-775 7975)(-525 7975);
WIRE 16 -1 (-775 7850)(-775 7975);
WIRE 16 -1 (-5250 5800)(-5250 5875);
WIRE 16 -1 (-5050 7000)(-5050 6950);
WIRE 16 -1 (-4825 4200)(-4825 4150);
WIRE 16 -1 (-4125 6325)(-4125 6250);
WIRE 16 -1 (-2825 4450)(-2825 4375);
WIRE 16 -1 (-2675 4450)(-2825 4450);
WIRE 16 -1 (-1625 4950)(-1625 4875);
WIRE 16 -1 (-5025 8525)(-5025 8600);
WIRE 16 -1 (-4000 9050)(-4000 8975);
WIRE 16 -1 (-2725 7150)(-2725 7225);
WIRE 16 -1 (-1525 7675)(-1525 7600);
WIRE 16 -1 (-4775 5625)(-3775 5625);
WIRE 16 -1 (-3775 6075)(-4450 6075);
FORCEPROP 0 LAST CDS_PHYS_NET_NAME SMB_2_BMC_GPU_BUF_R_SCL
J 0
(-4335 6123);
PAINT MONO (-4335 6123);
DISPLAY INVISIBLE (-4335 6123);
FORCEPROP 2 LAST SIG_NAME SMB_2_BMC_GPU_BUF_R_SCL
J 0
(-4360 6085);
DISPLAY 0.510638 (-4360 6085);
PAINT WHITE (-4360 6085);
WIRE 16 -1 (-3775 5625)(-3775 6075);
WIRE 16 -1 (-3775 6075)(-3375 6075);
WIRE 16 -1 (-3375 6300)(-3375 6075);
WIRE 16 -1 (-2925 6075)(-3375 6075);
WIRE 16 -1 (-3675 5550)(-4775 5550);
WIRE 16 -1 (-3675 5975)(-4450 5975);
FORCEPROP 0 LAST CDS_PHYS_NET_NAME SMB_2_BMC_GPU_BUF_R_SDA
J 0
(-4335 6023);
PAINT MONO (-4335 6023);
DISPLAY INVISIBLE (-4335 6023);
FORCEPROP 2 LAST SIG_NAME SMB_2_BMC_GPU_BUF_R_SDA
J 0
(-4360 5985);
DISPLAY 0.510638 (-4360 5985);
PAINT WHITE (-4360 5985);
WIRE 16 -1 (-3675 5550)(-3675 5975);
WIRE 16 -1 (-3675 5975)(-3125 5975);
WIRE 16 -1 (-3125 6300)(-3125 5975);
WIRE 16 -1 (-2925 5975)(-3125 5975);
WIRE 16 -1 (-3000 3825)(-2425 3825);
WIRE 16 -1 (-3000 4650)(-3000 3825);
WIRE 16 -1 (-3000 4650)(-3950 4650);
FORCEPROP 0 LAST CDS_PHYS_NET_NAME I3C_BMC_SWB_R_SCL
J 0
(-4635 4698);
PAINT MONO (-4635 4698);
DISPLAY INVISIBLE (-4635 4698);
WIRE 16 -1 (-2675 4650)(-3000 4650);
FORCEPROP 2 LAST SIG_NAME I3C_BMC_SWB_R_SCL
J 2
(-2985 4660);
DISPLAY 0.510638 (-2985 4660);
PAINT WHITE (-2985 4660);
WIRE 16 -1 (-2875 3900)(-2425 3900);
WIRE 16 -1 (-2875 4550)(-2875 3900);
WIRE 16 -1 (-3950 4550)(-2875 4550);
FORCEPROP 0 LAST CDS_PHYS_NET_NAME I3C_BMC_SWB_R_SDA
J 0
(-4635 4598);
PAINT MONO (-4635 4598);
DISPLAY INVISIBLE (-4635 4598);
FORCEPROP 2 LAST SIG_NAME I3C_BMC_SWB_R_SDA
J 2
(-2985 4560);
DISPLAY 0.510638 (-2985 4560);
PAINT WHITE (-2985 4560);
WIRE 16 -1 (-2675 4550)(-2875 4550);
WIRE 16 -1 (-700 4925)(-700 4550);
WIRE 16 -1 (-250 4550)(-700 4550);
WIRE 16 -1 (-900 4550)(-1875 4550);
FORCEPROP 0 LAST CDS_PHYS_NET_NAME I3C_BMC_SWB_BUF_R_SDA
J 0
(-1760 4598);
PAINT MONO (-1760 4598);
DISPLAY INVISIBLE (-1760 4598);
FORCEPROP 2 LAST SIG_NAME I3C_BMC_SWB_BUF_R_SDA
J 0
(-1710 4560);
DISPLAY 0.510638 (-1710 4560);
PAINT WHITE (-1710 4560);
WIRE 16 -1 (-700 4550)(-900 4550);
WIRE 16 -1 (-900 3900)(-900 4550);
WIRE 16 -1 (-2225 3900)(-900 3900);
WIRE 16 -1 (-450 4925)(-450 4650);
WIRE 16 -1 (-250 4650)(-450 4650);
WIRE 16 -1 (-775 4650)(-1875 4650);
FORCEPROP 0 LAST CDS_PHYS_NET_NAME I3C_BMC_SWB_BUF_R_SCL
J 0
(-1760 4698);
PAINT MONO (-1760 4698);
DISPLAY INVISIBLE (-1760 4698);
FORCEPROP 2 LAST SIG_NAME I3C_BMC_SWB_BUF_R_SCL
J 0
(-1710 4660);
DISPLAY 0.510638 (-1710 4660);
PAINT WHITE (-1710 4660);
WIRE 16 -1 (-450 4650)(-775 4650);
WIRE 16 -1 (-775 3825)(-775 4650);
WIRE 16 -1 (-2225 3825)(-775 3825);
WIRE 16 -1 (-1725 4750)(-1875 4750);
WIRE 16 -1 (-1625 5150)(-1625 5225);
WIRE 16 -1 (-1725 5225)(-1725 4750);
WIRE 16 -1 (-1725 5225)(-1625 5225);
WIRE 16 -1 (1125 4650)(-50 4650);
FORCEPROP 0 LAST CDS_PHYS_NET_NAME I3C_BMC_SWB_BUF_SCL
J 0
(65 4698);
PAINT MONO (65 4698);
DISPLAY INVISIBLE (65 4698);
FORCEPROP 2 LAST SIG_NAME I3C_BMC_SWB_BUF_SCL
J 0
(515 4660);
DISPLAY 0.510638 (515 4660);
PAINT WHITE (515 4660);
WIRE 16 -1 (-1550 5975)(-2725 5975);
FORCEPROP 0 LAST CDS_PHYS_NET_NAME SMB_2_BMC_GPU_BUF_SDA
J 0
(-2610 6023);
PAINT MONO (-2610 6023);
DISPLAY INVISIBLE (-2610 6023);
FORCEPROP 2 LAST SIG_NAME SMB_2_BMC_GPU_BUF_SDA
J 0
(-2160 5985);
DISPLAY 0.510638 (-2160 5985);
PAINT WHITE (-2160 5985);
WIRE 16 -1 (-1550 6075)(-2725 6075);
FORCEPROP 0 LAST CDS_PHYS_NET_NAME SMB_2_BMC_GPU_BUF_SCL
J 0
(-2610 6123);
PAINT MONO (-2610 6123);
DISPLAY INVISIBLE (-2610 6123);
FORCEPROP 2 LAST SIG_NAME SMB_2_BMC_GPU_BUF_SCL
J 0
(-2160 6085);
DISPLAY 0.510638 (-2160 6085);
PAINT WHITE (-2160 6085);
WIRE 16 -1 (1050 7325)(-125 7325);
FORCEPROP 0 LAST CDS_PHYS_NET_NAME SMB_1_BMC_GPU_BUF_SDA
J 0
(-10 7373);
PAINT MONO (-10 7373);
DISPLAY INVISIBLE (-10 7373);
FORCEPROP 2 LAST SIG_NAME SMB_1_BMC_GPU_BUF_SDA
J 0
(440 7335);
DISPLAY 0.510638 (440 7335);
PAINT WHITE (440 7335);
WIRE 16 -1 (1050 7425)(-125 7425);
FORCEPROP 0 LAST CDS_PHYS_NET_NAME SMB_1_BMC_GPU_BUF_SCL
J 0
(-10 7473);
PAINT MONO (-10 7473);
DISPLAY INVISIBLE (-10 7473);
FORCEPROP 2 LAST SIG_NAME SMB_1_BMC_GPU_BUF_SCL
J 0
(440 7435);
DISPLAY 0.510638 (440 7435);
PAINT WHITE (440 7435);
WIRE 16 -1 (-525 7850)(-525 7975);
WIRE 16 -1 (-450 5125)(-450 5250);
WIRE 16 -1 (1125 4550)(-50 4550);
FORCEPROP 0 LAST CDS_PHYS_NET_NAME I3C_BMC_SWB_BUF_SDA
J 0
(65 4598);
PAINT MONO (65 4598);
DISPLAY INVISIBLE (65 4598);
FORCEPROP 2 LAST SIG_NAME I3C_BMC_SWB_BUF_SDA
J 0
(515 4560);
DISPLAY 0.510638 (515 4560);
PAINT WHITE (515 4560);
WIRE 16 2175 (-375 4425)(275 4425);
WIRE 16 2175 (275 4600)(275 4425);
WIRE 16 2175 (-375 4600)(-375 4425);
WIRE 16 2175 (-375 4600)(275 4600);
WIRE 16 -1 (-775 7650)(-775 7425);
WIRE 16 -1 (-325 7425)(-775 7425);
WIRE 16 -1 (-1175 7425)(-1850 7425);
FORCEPROP 0 LAST CDS_PHYS_NET_NAME SMB_1_BMC_GPU_BUF_R_SCL
J 0
(-1735 7473);
PAINT MONO (-1735 7473);
DISPLAY INVISIBLE (-1735 7473);
FORCEPROP 2 LAST SIG_NAME SMB_1_BMC_GPU_BUF_R_SCL
J 0
(-1760 7435);
DISPLAY 0.510638 (-1760 7435);
PAINT WHITE (-1760 7435);
WIRE 16 -1 (-775 7425)(-1175 7425);
WIRE 16 -1 (-1175 6975)(-1175 7425);
WIRE 16 -1 (-2175 6975)(-1175 6975);
WIRE 16 -1 (-525 7650)(-525 7325);
WIRE 16 -1 (-325 7325)(-525 7325);
WIRE 16 -1 (-1075 7325)(-1850 7325);
FORCEPROP 0 LAST CDS_PHYS_NET_NAME SMB_1_BMC_GPU_BUF_R_SDA
J 0
(-1735 7373);
PAINT MONO (-1735 7373);
DISPLAY INVISIBLE (-1735 7373);
FORCEPROP 2 LAST SIG_NAME SMB_1_BMC_GPU_BUF_R_SDA
J 0
(-1760 7335);
DISPLAY 0.510638 (-1760 7335);
PAINT WHITE (-1760 7335);
WIRE 16 -1 (-1075 7325)(-525 7325);
WIRE 16 -1 (-1075 6900)(-2175 6900);
WIRE 16 -1 (-1075 6900)(-1075 7325);
WIRE 16 -1 (-1525 7875)(-1525 7950);
WIRE 16 -1 (-1700 7525)(-1850 7525);
WIRE 16 -1 (-1325 8700)(-2500 8700);
FORCEPROP 0 LAST CDS_PHYS_NET_NAME SMB_BMC_SWB_BUF_SDA
J 0
(-2385 8748);
PAINT MONO (-2385 8748);
DISPLAY INVISIBLE (-2385 8748);
FORCEPROP 2 LAST SIG_NAME SMB_BMC_SWB_BUF_SDA
J 0
(-1935 8710);
DISPLAY 0.510638 (-1935 8710);
PAINT WHITE (-1935 8710);
WIRE 16 -1 (-1325 8800)(-2500 8800);
FORCEPROP 0 LAST CDS_PHYS_NET_NAME SMB_BMC_SWB_BUF_SCL
J 0
(-2385 8848);
PAINT MONO (-2385 8848);
DISPLAY INVISIBLE (-2385 8848);
FORCEPROP 2 LAST SIG_NAME SMB_BMC_SWB_BUF_SCL
J 0
(-1935 8810);
DISPLAY 0.510638 (-1935 8810);
PAINT WHITE (-1935 8810);
WIRE 16 -1 (-2725 7225)(-2650 7225);
WIRE 16 -1 (-4000 7525)(-2650 7525);
FORCEPROP 0 LAST CDS_PHYS_NET_NAME SMB_BMC_GPU_EN_R1
J 0
(-3885 7573);
PAINT MONO (-3885 7573);
DISPLAY INVISIBLE (-3885 7573);
FORCEPROP 2 LAST SIG_NAME SMB_BMC_GPU_EN_R1
J 0
(-3585 7535);
DISPLAY 0.510638 (-3585 7535);
PAINT WHITE (-3585 7535);
WIRE 16 2175 (-3200 8925)(-2650 8925);
WIRE 16 2175 (-2650 9275)(-2650 8925);
WIRE 16 2175 (-3200 9275)(-3200 8925);
WIRE 16 2175 (-3200 9275)(-2650 9275);
WIRE 16 -1 (-2900 9225)(-2900 9350);
WIRE 16 -1 (-4000 9250)(-4000 9325);
WIRE 16 -1 (-4225 8900)(-4175 8900);
WIRE 16 -1 (-2700 8700)(-2900 8700);
WIRE 16 -1 (-2900 9025)(-2900 8700);
WIRE 16 -1 (-4225 8700)(-3450 8700);
FORCEPROP 0 LAST CDS_PHYS_NET_NAME SMB_BMC_SWB_BUF_R_SDA
J 0
(-4210 8748);
PAINT MONO (-4210 8748);
DISPLAY INVISIBLE (-4210 8748);
FORCEPROP 2 LAST SIG_NAME SMB_BMC_SWB_BUF_R_SDA
J 0
(-4160 8710);
DISPLAY 0.510638 (-4160 8710);
PAINT WHITE (-4160 8710);
WIRE 16 -1 (-3450 8700)(-2900 8700);
WIRE 16 -1 (-3450 8275)(-4550 8275);
WIRE 16 -1 (-3450 8275)(-3450 8700);
WIRE 16 -1 (-3150 9025)(-3150 8800);
WIRE 16 -1 (-2700 8800)(-3150 8800);
WIRE 16 -1 (-4225 8800)(-3550 8800);
FORCEPROP 0 LAST CDS_PHYS_NET_NAME SMB_BMC_SWB_BUF_R_SCL
J 0
(-4210 8848);
PAINT MONO (-4210 8848);
DISPLAY INVISIBLE (-4210 8848);
FORCEPROP 2 LAST SIG_NAME SMB_BMC_SWB_BUF_R_SCL
J 0
(-4160 8810);
DISPLAY 0.510638 (-4160 8810);
PAINT WHITE (-4160 8810);
WIRE 16 -1 (-3550 8800)(-3150 8800);
WIRE 16 -1 (-3550 8350)(-3550 8800);
WIRE 16 -1 (-4550 8350)(-3550 8350);
WIRE 16 -1 (-2950 6975)(-2375 6975);
WIRE 16 -1 (-2950 7425)(-4000 7425);
FORCEPROP 0 LAST CDS_PHYS_NET_NAME SMB_1_BMC_GPU_R_SCL
J 0
(-4660 7473);
PAINT MONO (-4660 7473);
DISPLAY INVISIBLE (-4660 7473);
FORCEPROP 2 LAST SIG_NAME SMB_1_BMC_GPU_R_SCL
J 2
(-3135 7435);
DISPLAY 0.510638 (-3135 7435);
PAINT WHITE (-3135 7435);
WIRE 16 -1 (-2950 6975)(-2950 7425);
WIRE 16 -1 (-2650 7425)(-2950 7425);
WIRE 16 -1 (-4200 7425)(-5225 7425);
FORCEPROP 0 LAST CDS_PHYS_NET_NAME SMB_1_BMC_GPU_SCL
J 0
(-5110 7473);
PAINT MONO (-5110 7473);
DISPLAY INVISIBLE (-5110 7473);
FORCEPROP 2 LAST SIG_NAME SMB_1_BMC_GPU_SCL
J 2
(-4435 7435);
DISPLAY 0.510638 (-4435 7435);
PAINT WHITE (-4435 7435);
WIRE 16 -1 (-4200 7325)(-5225 7325);
FORCEPROP 0 LAST CDS_PHYS_NET_NAME SMB_1_BMC_GPU_SDA
J 0
(-5110 7373);
PAINT MONO (-5110 7373);
DISPLAY INVISIBLE (-5110 7373);
FORCEPROP 2 LAST SIG_NAME SMB_1_BMC_GPU_SDA
J 2
(-4435 7335);
DISPLAY 0.510638 (-4435 7335);
PAINT WHITE (-4435 7335);
WIRE 16 -1 (-5325 8350)(-4750 8350);
WIRE 16 -1 (-5325 8800)(-6025 8800);
WIRE 16 -1 (-5325 8800)(-5325 8350);
WIRE 16 -1 (-5025 8800)(-5325 8800);
FORCEPROP 2 LAST SIG_NAME SMB_BMC_SWB_R_SCL
J 0
(-5660 8810);
DISPLAY 0.510638 (-5660 8810);
PAINT WHITE (-5660 8810);
WIRE 16 -1 (-4750 8275)(-5425 8275);
WIRE 16 -1 (-5425 8700)(-6025 8700);
WIRE 16 -1 (-5425 8700)(-5425 8275);
WIRE 16 -1 (-5025 8700)(-5425 8700);
FORCEPROP 2 LAST SIG_NAME SMB_BMC_SWB_R_SDA
J 0
(-5660 8710);
DISPLAY 0.510638 (-5660 8710);
PAINT WHITE (-5660 8710);
WIRE 16 -1 (-5050 7525)(-5225 7525);
WIRE 16 -1 (-5050 7525)(-5050 7200);
WIRE 16 -1 (-4200 7525)(-5050 7525);
FORCEPROP 2 LAST SIG_NAME SMB_BMC_GPU_EN
J 0
(-4835 7535);
DISPLAY 0.510638 (-4835 7535);
PAINT WHITE (-4835 7535);
WIRE 16 -1 (-5025 8900)(-6025 8900);
FORCEPROP 0 LAST CDS_PHYS_NET_NAME SMB_BMC_SWB_EN_R
J 0
(-5985 8948);
PAINT MONO (-5985 8948);
DISPLAY INVISIBLE (-5985 8948);
FORCEPROP 2 LAST SIG_NAME SMB_BMC_SWB_EN_R
J 0
(-5660 8910);
DISPLAY 0.510638 (-5660 8910);
PAINT WHITE (-5660 8910);
WIRE 16 -1 (-6225 8700)(-6925 8700);
FORCEPROP 0 LAST CDS_PHYS_NET_NAME SMB_BMC_SWB_SDA
J 0
(-6810 8748);
PAINT MONO (-6810 8748);
DISPLAY INVISIBLE (-6810 8748);
FORCEPROP 2 LAST SIG_NAME SMB_BMC_SWB_SDA
J 2
(-6460 8710);
DISPLAY 0.510638 (-6460 8710);
PAINT WHITE (-6460 8710);
WIRE 16 -1 (-6225 8900)(-6925 8900);
FORCEPROP 2 LAST SIG_NAME SMB_BMC_SWB_EN
J 0
(-6785 8910);
DISPLAY 0.510638 (-6785 8910);
PAINT WHITE (-6785 8910);
WIRE 16 -1 (-6225 8800)(-6925 8800);
FORCEPROP 0 LAST CDS_PHYS_NET_NAME SMB_BMC_SWB_SCL
J 0
(-6810 8848);
PAINT MONO (-6810 8848);
DISPLAY INVISIBLE (-6810 8848);
FORCEPROP 2 LAST SIG_NAME SMB_BMC_SWB_SCL
J 2
(-6460 8810);
DISPLAY 0.510638 (-6460 8810);
PAINT WHITE (-6460 8810);
WIRE 16 2175 (-5100 6850)(-4725 6850);
WIRE 16 2175 (-4725 7275)(-4725 6850);
WIRE 16 2175 (-5100 7275)(-5100 6850);
WIRE 16 2175 (-5100 7275)(-4725 7275);
WIRE 16 -1 (-3050 7325)(-4000 7325);
FORCEPROP 0 LAST CDS_PHYS_NET_NAME SMB_1_BMC_GPU_R_SDA
J 0
(-4660 7373);
PAINT MONO (-4660 7373);
DISPLAY INVISIBLE (-4660 7373);
FORCEPROP 2 LAST SIG_NAME SMB_1_BMC_GPU_R_SDA
J 2
(-3135 7335);
DISPLAY 0.510638 (-3135 7335);
PAINT WHITE (-3135 7335);
WIRE 16 -1 (-2650 7325)(-3050 7325);
WIRE 16 -1 (-3050 6900)(-3050 7325);
WIRE 16 -1 (-2375 6900)(-3050 6900);
WIRE 16 -1 (-3950 4750)(-2675 4750);
FORCEPROP 0 LAST CDS_PHYS_NET_NAME SMB_BMC_SWB_EN_R2
J 0
(-1085 4798);
PAINT MONO (-1085 4798);
DISPLAY INVISIBLE (-1085 4798);
FORCEPROP 2 LAST SIG_NAME SMB_BMC_SWB_EN_R2
J 0
(-3535 4760);
DISPLAY 0.510638 (-3535 4760);
PAINT WHITE (-3535 4760);
WIRE 16 -1 (-3125 6500)(-3125 6625);
WIRE 16 -1 (-4125 6525)(-4125 6600);
WIRE 16 -1 (-4300 6175)(-4450 6175);
WIRE 16 2175 (-4300 4500)(-3650 4500);
WIRE 16 2175 (-3650 4625)(-3650 4500);
WIRE 16 2175 (-4300 4625)(-4300 4500);
WIRE 16 2175 (-4300 4625)(-3650 4625);
WIRE 16 -1 (-4825 4750)(-4825 4400);
WIRE 16 -1 (-4825 4750)(-4900 4750);
WIRE 16 -1 (-4150 4750)(-4825 4750);
FORCEPROP 2 LAST SIG_NAME SMB_BMC_SWB_EN
J 0
(-4785 4760);
DISPLAY 0.510638 (-4785 4760);
PAINT WHITE (-4785 4760);
WIRE 16 -1 (-4150 4650)(-4900 4650);
FORCEPROP 2 LAST SIG_NAME I3C_BMC_SWB_SCL
J 0
(-4785 4660);
DISPLAY 0.510638 (-4785 4660);
PAINT WHITE (-4785 4660);
WIRE 16 -1 (-4150 4550)(-4900 4550);
FORCEPROP 2 LAST SIG_NAME I3C_BMC_SWB_SDA
J 0
(-4785 4560);
DISPLAY 0.510638 (-4785 4560);
PAINT WHITE (-4785 4560);
WIRE 16 -1 (-4975 5550)(-5650 5550);
WIRE 16 -1 (-5650 5975)(-5650 5550);
WIRE 16 -1 (-5650 5975)(-6075 5975);
FORCEPROP 2 LAST SIG_NAME SMB_2_BMC_GPU_R_SDA
J 0
(-5810 5985);
DISPLAY 0.404255 (-5810 5985);
PAINT WHITE (-5810 5985);
WIRE 16 -1 (-5250 5975)(-5650 5975);
WIRE 16 -1 (-5550 5625)(-4975 5625);
WIRE 16 -1 (-5550 6075)(-6075 6075);
FORCEPROP 2 LAST SIG_NAME SMB_2_BMC_GPU_R_SCL
J 0
(-5812 6085);
DISPLAY 0.404255 (-5812 6085);
PAINT WHITE (-5812 6085);
WIRE 16 -1 (-5550 6075)(-5550 5625);
WIRE 16 -1 (-5250 6075)(-5550 6075);
WIRE 16 -1 (-6075 6175)(-5250 6175);
FORCEPROP 0 LAST CDS_PHYS_NET_NAME SMB_BMC_GPU_EN_R3
J 0
(-6010 6223);
PAINT MONO (-6010 6223);
DISPLAY INVISIBLE (-6010 6223);
FORCEPROP 2 LAST SIG_NAME SMB_BMC_GPU_EN_R3
J 0
(-5785 6185);
DISPLAY 0.510638 (-5785 6185);
PAINT WHITE (-5785 6185);
WIRE 16 -1 (-6275 5975)(-7000 5975);
FORCEPROP 0 LAST CDS_PHYS_NET_NAME SMB_2_BMC_GPU_SDA
J 0
(-6885 6023);
PAINT MONO (-6885 6023);
DISPLAY INVISIBLE (-6885 6023);
FORCEPROP 2 LAST SIG_NAME SMB_2_BMC_GPU_SDA
J 2
(-6460 5985);
DISPLAY 0.510638 (-6460 5985);
PAINT WHITE (-6460 5985);
WIRE 16 -1 (-6275 6075)(-7000 6075);
FORCEPROP 0 LAST CDS_PHYS_NET_NAME SMB_2_BMC_GPU_SCL
J 0
(-6885 6123);
PAINT MONO (-6885 6123);
DISPLAY INVISIBLE (-6885 6123);
FORCEPROP 2 LAST SIG_NAME SMB_2_BMC_GPU_SCL
J 2
(-6460 6085);
DISPLAY 0.510638 (-6460 6085);
PAINT WHITE (-6460 6085);
WIRE 16 -1 (-6275 6175)(-7000 6175);
FORCEPROP 2 LAST SIG_NAME SMB_BMC_GPU_EN
J 0
(-6860 6185);
DISPLAY 0.510638 (-6860 6185);
PAINT WHITE (-6860 6185);
DOT 1 (-5650 5975);
DOT 1 (-5550 6075);
DOT 1 (-4825 4750);
DOT 1 (-2875 4550);
DOT 1 (-3000 4650);
DOT 1 (-4300 6600);
DOT 1 (-3775 6075);
DOT 1 (-3675 5975);
DOT 1 (-3375 6075);
DOT 1 (-3375 6625);
DOT 1 (-3125 5975);
DOT 1 (-900 4550);
DOT 1 (-5050 7525);
DOT 1 (-5425 8700);
DOT 1 (-5325 8800);
DOT 1 (-2950 7425);
DOT 1 (-3050 7325);
DOT 1 (-3450 8700);
DOT 1 (-3550 8800);
DOT 1 (-3150 8800);
DOT 1 (-2900 8700);
DOT 1 (-4175 9325);
DOT 1 (-3150 9350);
DOT 1 (-1700 7950);
DOT 1 (-1175 7425);
DOT 1 (-1075 7325);
DOT 1 (-700 4550);
DOT 1 (-775 4650);
DOT 1 (-450 4650);
DOT 1 (-700 5250);
DOT 1 (-775 7425);
DOT 1 (-525 7325);
DOT 1 (-775 7975);
DOT 1 (-1725 5225);
FORCENOTE
202120215 ADD R4603 
(-5425 6775) 0;
DISPLAY LEFT (-5425 6775);
DISPLAY 1.063830 (-5425 6775);
PAINT WHITE (-5425 6775);
FORCENOTE
I3C FROM BMC
(-4025 4325) 0;
DISPLAY LEFT (-4025 4325);
DISPLAY 1.595745 (-4025 4325);
PAINT WHITE (-4025 4325);
FORCENOTE
20221221 CHANGE R3111 TO 0 OHM
(-4525 4425) 0;
DISPLAY LEFT (-4525 4425);
DISPLAY 0.851064 (-4525 4425);
PAINT WHITE (-4525 4425);
FORCENOTE
20221222 CHANGE R2667,R2669 TO 10K OHM 
(-2875 9300) 0;
DISPLAY LEFT (-2875 9300);
DISPLAY 0.680851 (-2875 9300);
PAINT WHITE (-2875 9300);
FORCENOTE
20210607 MODIFY FOR GT
(-4350 9825) 0;
DISPLAY LEFT (-4350 9825);
DISPLAY 2.510638 (-4350 9825);
PAINT PINK (-4350 9825);
FORCENOTE
20221222 CHANGE R2674 TO 27.4 OHM
(-600 4375) 0;
DISPLAY LEFT (-600 4375);
DISPLAY 0.851064 (-600 4375);
PAINT WHITE (-600 4375);
QUIT
